(kicad_sch
	(version 20250114)
	(generator "eeschema")
	(generator_version "9.0")
	(paper "A3")
	(title_block
		(title "usb-c-power-adapter")
		(date "2025-06-24")
		(rev "1.1.2")
		(company "Antmicro")
		(comment 1 "www.antmicro.com")
	)
	(bus_alias "I2C"
		(members "SDA" "SCL")
	)
	(rectangle
		(start 205.74 106.68)
		(end 284.48 153.67)
		(stroke
			(width 0)
			(type dash)
		)
		(fill
			(type none)
		)
	)
	(rectangle
		(start 124.46 106.68)
		(end 198.12 185.42)
		(stroke
			(width 0)
			(type dash)
		)
		(fill
			(type none)
		)
	)
	(rectangle
		(start 205.74 158.75)
		(end 252.73 185.42)
		(stroke
			(width 0)
			(type dash)
		)
		(fill
			(type none)
		)
	)
	(rectangle
		(start 124.46 27.94)
		(end 358.14 101.6)
		(stroke
			(width 0)
			(type dash)
		)
		(fill
			(type none)
		)
	)
	(rectangle
		(start 30.48 27.94)
		(end 119.38 120.65)
		(stroke
			(width 0)
			(type dash)
		)
		(fill
			(type none)
		)
	)
	(text "USB-C PD Controller"
		(exclude_from_sim no)
		(at 218.44 35.56 0)
		(effects
			(font
				(size 3 3)
			)
			(justify left bottom)
		)
	)
	(text "LED Indicators\n"
		(exclude_from_sim no)
		(at 232.41 114.3 0)
		(effects
			(font
				(size 2.54 2.54)
			)
			(justify left bottom)
		)
	)
	(text "VBUS input present\n"
		(exclude_from_sim no)
		(at 213.36 118.11 0)
		(effects
			(font
				(size 1.27 1.27)
			)
			(justify left bottom)
		)
	)
	(text "Mounting pad\n"
		(exclude_from_sim no)
		(at 214.63 163.83 0)
		(effects
			(font
				(size 2.54 2.54)
			)
			(justify left bottom)
		)
	)
	(text "QWIIC I2C Connector"
		(exclude_from_sim no)
		(at 137.16 114.3 0)
		(effects
			(font
				(size 3 3)
			)
			(justify left bottom)
		)
	)
	(text "USB-C PD Connector\n"
		(exclude_from_sim no)
		(at 50.8 35.56 0)
		(effects
			(font
				(size 3 3)
			)
			(justify left bottom)
		)
	)
	(junction
		(at 176.53 137.16)
		(diameter 0)
		(color 0 0 0 0)
	)
	(junction
		(at 292.1 60.96)
		(diameter 0)
		(color 0 0 0 0)
	)
	(junction
		(at 147.32 142.24)
		(diameter 0)
		(color 0 0 0 0)
	)
	(junction
		(at 163.83 134.62)
		(diameter 0)
		(color 0 0 0 0)
	)
	(junction
		(at 105.41 53.34)
		(diameter 0)
		(color 0 0 0 0)
	)
	(junction
		(at 67.31 88.9)
		(diameter 0)
		(color 0 0 0 0)
	)
	(junction
		(at 173.99 139.7)
		(diameter 0)
		(color 0 0 0 0)
	)
	(junction
		(at 156.21 72.39)
		(diameter 0)
		(color 0 0 0 0)
	)
	(junction
		(at 181.61 50.8)
		(diameter 0)
		(color 0 0 0 0)
	)
	(junction
		(at 95.25 53.34)
		(diameter 0)
		(color 0 0 0 0)
	)
	(junction
		(at 146.05 59.69)
		(diameter 0)
		(color 0 0 0 0)
	)
	(junction
		(at 292.1 73.66)
		(diameter 0)
		(color 0 0 0 0)
	)
	(junction
		(at 215.9 88.9)
		(diameter 0)
		(color 0 0 0 0)
	)
	(junction
		(at 179.07 137.16)
		(diameter 0)
		(color 0 0 0 0)
	)
	(junction
		(at 198.12 60.96)
		(diameter 0)
		(color 0 0 0 0)
	)
	(junction
		(at 304.8 73.66)
		(diameter 0)
		(color 0 0 0 0)
	)
	(junction
		(at 215.9 68.58)
		(diameter 0)
		(color 0 0 0 0)
	)
	(junction
		(at 171.45 139.7)
		(diameter 0)
		(color 0 0 0 0)
	)
	(junction
		(at 320.04 60.96)
		(diameter 0)
		(color 0 0 0 0)
	)
	(junction
		(at 194.31 55.88)
		(diameter 0)
		(color 0 0 0 0)
	)
	(junction
		(at 86.36 53.34)
		(diameter 0)
		(color 0 0 0 0)
	)
	(junction
		(at 326.39 60.96)
		(diameter 0)
		(color 0 0 0 0)
	)
	(junction
		(at 146.05 72.39)
		(diameter 0)
		(color 0 0 0 0)
	)
	(junction
		(at 248.92 88.9)
		(diameter 0)
		(color 0 0 0 0)
	)
	(junction
		(at 215.9 71.12)
		(diameter 0)
		(color 0 0 0 0)
	)
	(no_connect
		(at 66.04 66.04)
	)
	(no_connect
		(at 66.04 78.74)
	)
	(no_connect
		(at 148.59 165.1)
	)
	(no_connect
		(at 66.04 81.28)
	)
	(no_connect
		(at 66.04 68.58)
	)
	(no_connect
		(at 66.04 71.12)
	)
	(no_connect
		(at 66.04 73.66)
	)
	(wire
		(pts
			(xy 186.69 55.88) (xy 194.31 55.88)
		)
		(stroke
			(width 0)
			(type default)
		)
	)
	(wire
		(pts
			(xy 261.62 53.34) (xy 247.65 53.34)
		)
		(stroke
			(width 0)
			(type default)
		)
	)
	(wire
		(pts
			(xy 176.53 137.16) (xy 176.53 143.51)
		)
		(stroke
			(width 0)
			(type default)
		)
	)
	(wire
		(pts
			(xy 156.21 83.82) (xy 172.72 83.82)
		)
		(stroke
			(width 0)
			(type default)
		)
	)
	(wire
		(pts
			(xy 147.32 142.24) (xy 147.32 148.59)
		)
		(stroke
			(width 0)
			(type default)
		)
	)
	(wire
		(pts
			(xy 186.69 46.99) (xy 186.69 55.88)
		)
		(stroke
			(width 0)
			(type default)
		)
	)
	(wire
		(pts
			(xy 106.68 97.79) (xy 99.06 97.79)
		)
		(stroke
			(width 0)
			(type default)
		)
	)
	(wire
		(pts
			(xy 66.04 86.36) (xy 67.31 86.36)
		)
		(stroke
			(width 0)
			(type default)
		)
	)
	(wire
		(pts
			(xy 205.74 68.58) (xy 215.9 68.58)
		)
		(stroke
			(width 0)
			(type default)
		)
	)
	(wire
		(pts
			(xy 247.65 76.2) (xy 269.24 76.2)
		)
		(stroke
			(width 0)
			(type default)
		)
	)
	(wire
		(pts
			(xy 106.68 82.55) (xy 99.06 82.55)
		)
		(stroke
			(width 0)
			(type default)
		)
	)
	(wire
		(pts
			(xy 248.92 86.36) (xy 248.92 88.9)
		)
		(stroke
			(width 0)
			(type default)
		)
	)
	(wire
		(pts
			(xy 66.04 53.34) (xy 86.36 53.34)
		)
		(stroke
			(width 0)
			(type default)
		)
	)
	(wire
		(pts
			(xy 215.9 71.12) (xy 215.9 73.66)
		)
		(stroke
			(width 0)
			(type default)
		)
	)
	(wire
		(pts
			(xy 66.04 58.42) (xy 73.66 58.42)
		)
		(stroke
			(width 0)
			(type default)
		)
	)
	(wire
		(pts
			(xy 171.45 124.46) (xy 171.45 127)
		)
		(stroke
			(width 0)
			(type default)
		)
	)
	(wire
		(pts
			(xy 205.74 81.28) (xy 217.17 81.28)
		)
		(stroke
			(width 0)
			(type default)
		)
	)
	(wire
		(pts
			(xy 106.68 78.74) (xy 106.68 80.01)
		)
		(stroke
			(width 0)
			(type default)
		)
	)
	(wire
		(pts
			(xy 339.09 87.63) (xy 339.09 88.9)
		)
		(stroke
			(width 0)
			(type default)
		)
	)
	(wire
		(pts
			(xy 146.05 59.69) (xy 146.05 63.5)
		)
		(stroke
			(width 0)
			(type default)
		)
	)
	(wire
		(pts
			(xy 260.35 127) (xy 260.35 130.81)
		)
		(stroke
			(width 0)
			(type default)
		)
	)
	(wire
		(pts
			(xy 247.65 78.74) (xy 260.35 78.74)
		)
		(stroke
			(width 0)
			(type default)
		)
	)
	(wire
		(pts
			(xy 179.07 132.08) (xy 179.07 137.16)
		)
		(stroke
			(width 0)
			(type default)
		)
	)
	(wire
		(pts
			(xy 304.8 73.66) (xy 309.88 73.66)
		)
		(stroke
			(width 0)
			(type default)
		)
	)
	(wire
		(pts
			(xy 241.3 143.51) (xy 241.3 148.59)
		)
		(stroke
			(width 0)
			(type default)
		)
	)
	(wire
		(pts
			(xy 156.21 83.82) (xy 156.21 80.01)
		)
		(stroke
			(width 0)
			(type default)
		)
	)
	(wire
		(pts
			(xy 314.96 73.66) (xy 326.39 73.66)
		)
		(stroke
			(width 0)
			(type default)
		)
	)
	(wire
		(pts
			(xy 163.83 124.46) (xy 163.83 127)
		)
		(stroke
			(width 0)
			(type default)
		)
	)
	(wire
		(pts
			(xy 194.31 54.61) (xy 194.31 55.88)
		)
		(stroke
			(width 0)
			(type default)
		)
	)
	(wire
		(pts
			(xy 105.41 60.96) (xy 105.41 59.69)
		)
		(stroke
			(width 0)
			(type default)
		)
	)
	(wire
		(pts
			(xy 214.63 177.8) (xy 214.63 175.26)
		)
		(stroke
			(width 0)
			(type default)
		)
	)
	(wire
		(pts
			(xy 149.86 175.26) (xy 149.86 176.53)
		)
		(stroke
			(width 0)
			(type default)
		)
	)
	(wire
		(pts
			(xy 252.73 58.42) (xy 247.65 58.42)
		)
		(stroke
			(width 0)
			(type default)
		)
	)
	(wire
		(pts
			(xy 146.05 83.82) (xy 146.05 80.01)
		)
		(stroke
			(width 0)
			(type default)
		)
	)
	(wire
		(pts
			(xy 148.59 167.64) (xy 158.75 167.64)
		)
		(stroke
			(width 0)
			(type default)
		)
	)
	(wire
		(pts
			(xy 86.36 52.07) (xy 86.36 53.34)
		)
		(stroke
			(width 0)
			(type default)
		)
	)
	(wire
		(pts
			(xy 215.9 73.66) (xy 217.17 73.66)
		)
		(stroke
			(width 0)
			(type default)
		)
	)
	(wire
		(pts
			(xy 171.45 132.08) (xy 171.45 139.7)
		)
		(stroke
			(width 0)
			(type default)
		)
	)
	(wire
		(pts
			(xy 95.25 50.8) (xy 95.25 53.34)
		)
		(stroke
			(width 0)
			(type default)
		)
	)
	(wire
		(pts
			(xy 241.3 135.89) (xy 241.3 138.43)
		)
		(stroke
			(width 0)
			(type default)
		)
	)
	(wire
		(pts
			(xy 173.99 139.7) (xy 186.69 139.7)
		)
		(stroke
			(width 0)
			(type default)
		)
	)
	(wire
		(pts
			(xy 261.62 50.8) (xy 247.65 50.8)
		)
		(stroke
			(width 0)
			(type default)
		)
	)
	(wire
		(pts
			(xy 106.68 80.01) (xy 99.06 80.01)
		)
		(stroke
			(width 0)
			(type default)
		)
	)
	(wire
		(pts
			(xy 146.05 72.39) (xy 156.21 72.39)
		)
		(stroke
			(width 0)
			(type default)
		)
	)
	(wire
		(pts
			(xy 171.45 139.7) (xy 173.99 139.7)
		)
		(stroke
			(width 0)
			(type default)
		)
	)
	(wire
		(pts
			(xy 215.9 71.12) (xy 217.17 71.12)
		)
		(stroke
			(width 0)
			(type default)
		)
	)
	(wire
		(pts
			(xy 312.42 60.96) (xy 320.04 60.96)
		)
		(stroke
			(width 0)
			(type default)
		)
	)
	(wire
		(pts
			(xy 242.57 148.59) (xy 241.3 148.59)
		)
		(stroke
			(width 0)
			(type default)
		)
	)
	(wire
		(pts
			(xy 269.24 91.44) (xy 269.24 92.71)
		)
		(stroke
			(width 0)
			(type default)
		)
	)
	(wire
		(pts
			(xy 67.31 88.9) (xy 66.04 88.9)
		)
		(stroke
			(width 0)
			(type default)
		)
	)
	(wire
		(pts
			(xy 144.78 137.16) (xy 176.53 137.16)
		)
		(stroke
			(width 0)
			(type default)
		)
	)
	(wire
		(pts
			(xy 260.35 143.51) (xy 260.35 148.59)
		)
		(stroke
			(width 0)
			(type default)
		)
	)
	(wire
		(pts
			(xy 181.61 46.99) (xy 181.61 50.8)
		)
		(stroke
			(width 0)
			(type default)
		)
	)
	(wire
		(pts
			(xy 106.68 114.3) (xy 99.06 114.3)
		)
		(stroke
			(width 0)
			(type default)
		)
	)
	(wire
		(pts
			(xy 163.83 134.62) (xy 163.83 142.24)
		)
		(stroke
			(width 0)
			(type default)
		)
	)
	(wire
		(pts
			(xy 215.9 91.44) (xy 215.9 88.9)
		)
		(stroke
			(width 0)
			(type default)
		)
	)
	(wire
		(pts
			(xy 179.07 124.46) (xy 179.07 127)
		)
		(stroke
			(width 0)
			(type default)
		)
	)
	(wire
		(pts
			(xy 326.39 58.42) (xy 326.39 60.96)
		)
		(stroke
			(width 0)
			(type default)
		)
	)
	(wire
		(pts
			(xy 146.05 74.93) (xy 146.05 72.39)
		)
		(stroke
			(width 0)
			(type default)
		)
	)
	(wire
		(pts
			(xy 304.8 67.31) (xy 304.8 73.66)
		)
		(stroke
			(width 0)
			(type default)
		)
	)
	(wire
		(pts
			(xy 156.21 64.77) (xy 156.21 59.69)
		)
		(stroke
			(width 0)
			(type default)
		)
	)
	(wire
		(pts
			(xy 173.99 146.05) (xy 173.99 139.7)
		)
		(stroke
			(width 0)
			(type default)
		)
	)
	(wire
		(pts
			(xy 148.59 170.18) (xy 158.75 170.18)
		)
		(stroke
			(width 0)
			(type default)
		)
	)
	(wire
		(pts
			(xy 255.27 71.12) (xy 247.65 71.12)
		)
		(stroke
			(width 0)
			(type default)
		)
	)
	(wire
		(pts
			(xy 173.99 146.05) (xy 179.07 146.05)
		)
		(stroke
			(width 0)
			(type default)
		)
	)
	(wire
		(pts
			(xy 292.1 73.66) (xy 292.1 76.2)
		)
		(stroke
			(width 0)
			(type default)
		)
	)
	(wire
		(pts
			(xy 213.36 83.82) (xy 217.17 83.82)
		)
		(stroke
			(width 0)
			(type default)
		)
	)
	(wire
		(pts
			(xy 205.74 71.12) (xy 215.9 71.12)
		)
		(stroke
			(width 0)
			(type default)
		)
	)
	(wire
		(pts
			(xy 205.74 78.74) (xy 217.17 78.74)
		)
		(stroke
			(width 0)
			(type default)
		)
	)
	(wire
		(pts
			(xy 146.05 57.15) (xy 146.05 59.69)
		)
		(stroke
			(width 0)
			(type default)
		)
	)
	(wire
		(pts
			(xy 179.07 137.16) (xy 186.69 137.16)
		)
		(stroke
			(width 0)
			(type default)
		)
	)
	(wire
		(pts
			(xy 198.12 67.31) (xy 198.12 68.58)
		)
		(stroke
			(width 0)
			(type default)
		)
	)
	(wire
		(pts
			(xy 222.25 127) (xy 222.25 130.81)
		)
		(stroke
			(width 0)
			(type default)
		)
	)
	(wire
		(pts
			(xy 326.39 73.66) (xy 326.39 68.58)
		)
		(stroke
			(width 0)
			(type default)
		)
	)
	(wire
		(pts
			(xy 292.1 73.66) (xy 304.8 73.66)
		)
		(stroke
			(width 0)
			(type default)
		)
	)
	(wire
		(pts
			(xy 215.9 86.36) (xy 217.17 86.36)
		)
		(stroke
			(width 0)
			(type default)
		)
	)
	(wire
		(pts
			(xy 292.1 60.96) (xy 292.1 66.04)
		)
		(stroke
			(width 0)
			(type default)
		)
	)
	(wire
		(pts
			(xy 144.78 139.7) (xy 171.45 139.7)
		)
		(stroke
			(width 0)
			(type default)
		)
	)
	(wire
		(pts
			(xy 252.73 63.5) (xy 247.65 63.5)
		)
		(stroke
			(width 0)
			(type default)
		)
	)
	(wire
		(pts
			(xy 212.09 62.23) (xy 212.09 53.34)
		)
		(stroke
			(width 0)
			(type default)
		)
	)
	(wire
		(pts
			(xy 212.09 53.34) (xy 217.17 53.34)
		)
		(stroke
			(width 0)
			(type default)
		)
	)
	(wire
		(pts
			(xy 320.04 59.69) (xy 320.04 60.96)
		)
		(stroke
			(width 0)
			(type default)
		)
	)
	(wire
		(pts
			(xy 247.65 86.36) (xy 248.92 86.36)
		)
		(stroke
			(width 0)
			(type default)
		)
	)
	(wire
		(pts
			(xy 215.9 86.36) (xy 215.9 88.9)
		)
		(stroke
			(width 0)
			(type default)
		)
	)
	(wire
		(pts
			(xy 163.83 132.08) (xy 163.83 134.62)
		)
		(stroke
			(width 0)
			(type default)
		)
	)
	(wire
		(pts
			(xy 241.3 127) (xy 241.3 130.81)
		)
		(stroke
			(width 0)
			(type default)
		)
	)
	(wire
		(pts
			(xy 222.25 135.89) (xy 222.25 138.43)
		)
		(stroke
			(width 0)
			(type default)
		)
	)
	(wire
		(pts
			(xy 292.1 83.82) (xy 292.1 81.28)
		)
		(stroke
			(width 0)
			(type default)
		)
	)
	(wire
		(pts
			(xy 215.9 68.58) (xy 217.17 68.58)
		)
		(stroke
			(width 0)
			(type default)
		)
	)
	(wire
		(pts
			(xy 146.05 59.69) (xy 156.21 59.69)
		)
		(stroke
			(width 0)
			(type default)
		)
	)
	(wire
		(pts
			(xy 156.21 69.85) (xy 156.21 72.39)
		)
		(stroke
			(width 0)
			(type default)
		)
	)
	(wire
		(pts
			(xy 269.24 76.2) (xy 269.24 86.36)
		)
		(stroke
			(width 0)
			(type default)
		)
	)
	(wire
		(pts
			(xy 260.35 135.89) (xy 260.35 138.43)
		)
		(stroke
			(width 0)
			(type default)
		)
	)
	(wire
		(pts
			(xy 86.36 53.34) (xy 95.25 53.34)
		)
		(stroke
			(width 0)
			(type default)
		)
	)
	(wire
		(pts
			(xy 292.1 58.42) (xy 292.1 60.96)
		)
		(stroke
			(width 0)
			(type default)
		)
	)
	(wire
		(pts
			(xy 248.92 88.9) (xy 248.92 92.71)
		)
		(stroke
			(width 0)
			(type default)
		)
	)
	(wire
		(pts
			(xy 198.12 62.23) (xy 198.12 60.96)
		)
		(stroke
			(width 0)
			(type default)
		)
	)
	(wire
		(pts
			(xy 252.73 60.96) (xy 247.65 60.96)
		)
		(stroke
			(width 0)
			(type default)
		)
	)
	(wire
		(pts
			(xy 205.74 55.88) (xy 217.17 55.88)
		)
		(stroke
			(width 0)
			(type default)
		)
	)
	(wire
		(pts
			(xy 67.31 88.9) (xy 67.31 91.44)
		)
		(stroke
			(width 0)
			(type default)
		)
	)
	(wire
		(pts
			(xy 181.61 54.61) (xy 181.61 50.8)
		)
		(stroke
			(width 0)
			(type default)
		)
	)
	(wire
		(pts
			(xy 99.06 111.76) (xy 110.49 111.76)
		)
		(stroke
			(width 0)
			(type default)
		)
	)
	(wire
		(pts
			(xy 215.9 88.9) (xy 217.17 88.9)
		)
		(stroke
			(width 0)
			(type default)
		)
	)
	(wire
		(pts
			(xy 105.41 50.8) (xy 105.41 53.34)
		)
		(stroke
			(width 0)
			(type default)
		)
	)
	(wire
		(pts
			(xy 194.31 55.88) (xy 200.66 55.88)
		)
		(stroke
			(width 0)
			(type default)
		)
	)
	(wire
		(pts
			(xy 280.67 83.82) (xy 292.1 83.82)
		)
		(stroke
			(width 0)
			(type default)
		)
	)
	(wire
		(pts
			(xy 105.41 54.61) (xy 105.41 53.34)
		)
		(stroke
			(width 0)
			(type default)
		)
	)
	(wire
		(pts
			(xy 214.63 175.26) (xy 215.9 175.26)
		)
		(stroke
			(width 0)
			(type default)
		)
	)
	(wire
		(pts
			(xy 302.26 60.96) (xy 292.1 60.96)
		)
		(stroke
			(width 0)
			(type default)
		)
	)
	(wire
		(pts
			(xy 95.25 53.34) (xy 105.41 53.34)
		)
		(stroke
			(width 0)
			(type default)
		)
	)
	(wire
		(pts
			(xy 163.83 147.32) (xy 163.83 148.59)
		)
		(stroke
			(width 0)
			(type default)
		)
	)
	(wire
		(pts
			(xy 215.9 66.04) (xy 217.17 66.04)
		)
		(stroke
			(width 0)
			(type default)
		)
	)
	(wire
		(pts
			(xy 215.9 66.04) (xy 215.9 68.58)
		)
		(stroke
			(width 0)
			(type default)
		)
	)
	(wire
		(pts
			(xy 144.78 134.62) (xy 163.83 134.62)
		)
		(stroke
			(width 0)
			(type default)
		)
	)
	(wire
		(pts
			(xy 347.98 88.9) (xy 347.98 86.36)
		)
		(stroke
			(width 0)
			(type default)
		)
	)
	(wire
		(pts
			(xy 261.62 148.59) (xy 260.35 148.59)
		)
		(stroke
			(width 0)
			(type default)
		)
	)
	(wire
		(pts
			(xy 99.06 95.25) (xy 110.49 95.25)
		)
		(stroke
			(width 0)
			(type default)
		)
	)
	(wire
		(pts
			(xy 147.32 142.24) (xy 144.78 142.24)
		)
		(stroke
			(width 0)
			(type default)
		)
	)
	(wire
		(pts
			(xy 222.25 143.51) (xy 222.25 146.05)
		)
		(stroke
			(width 0)
			(type default)
		)
	)
	(wire
		(pts
			(xy 156.21 72.39) (xy 156.21 74.93)
		)
		(stroke
			(width 0)
			(type default)
		)
	)
	(wire
		(pts
			(xy 176.53 143.51) (xy 179.07 143.51)
		)
		(stroke
			(width 0)
			(type default)
		)
	)
	(wire
		(pts
			(xy 326.39 60.96) (xy 326.39 63.5)
		)
		(stroke
			(width 0)
			(type default)
		)
	)
	(wire
		(pts
			(xy 198.12 60.96) (xy 217.17 60.96)
		)
		(stroke
			(width 0)
			(type default)
		)
	)
	(wire
		(pts
			(xy 247.65 88.9) (xy 248.92 88.9)
		)
		(stroke
			(width 0)
			(type default)
		)
	)
	(wire
		(pts
			(xy 260.35 78.74) (xy 260.35 86.36)
		)
		(stroke
			(width 0)
			(type default)
		)
	)
	(wire
		(pts
			(xy 144.78 132.08) (xy 147.32 132.08)
		)
		(stroke
			(width 0)
			(type default)
		)
	)
	(wire
		(pts
			(xy 320.04 60.96) (xy 326.39 60.96)
		)
		(stroke
			(width 0)
			(type default)
		)
	)
	(wire
		(pts
			(xy 176.53 137.16) (xy 179.07 137.16)
		)
		(stroke
			(width 0)
			(type default)
		)
	)
	(wire
		(pts
			(xy 146.05 68.58) (xy 146.05 72.39)
		)
		(stroke
			(width 0)
			(type default)
		)
	)
	(wire
		(pts
			(xy 195.58 60.96) (xy 198.12 60.96)
		)
		(stroke
			(width 0)
			(type default)
		)
	)
	(wire
		(pts
			(xy 148.59 175.26) (xy 149.86 175.26)
		)
		(stroke
			(width 0)
			(type default)
		)
	)
	(wire
		(pts
			(xy 181.61 64.77) (xy 181.61 59.69)
		)
		(stroke
			(width 0)
			(type default)
		)
	)
	(wire
		(pts
			(xy 260.35 91.44) (xy 260.35 92.71)
		)
		(stroke
			(width 0)
			(type default)
		)
	)
	(wire
		(pts
			(xy 67.31 86.36) (xy 67.31 88.9)
		)
		(stroke
			(width 0)
			(type default)
		)
	)
	(wire
		(pts
			(xy 66.04 60.96) (xy 73.66 60.96)
		)
		(stroke
			(width 0)
			(type default)
		)
	)
	(wire
		(pts
			(xy 255.27 68.58) (xy 247.65 68.58)
		)
		(stroke
			(width 0)
			(type default)
		)
	)
	(wire
		(pts
			(xy 148.59 172.72) (xy 158.75 172.72)
		)
		(stroke
			(width 0)
			(type default)
		)
	)
	(wire
		(pts
			(xy 292.1 71.12) (xy 292.1 73.66)
		)
		(stroke
			(width 0)
			(type default)
		)
	)
	(wire
		(pts
			(xy 181.61 50.8) (xy 217.17 50.8)
		)
		(stroke
			(width 0)
			(type default)
		)
	)
	(wire
		(pts
			(xy 147.32 132.08) (xy 147.32 142.24)
		)
		(stroke
			(width 0)
			(type default)
		)
	)
	(label "CC1"
		(at 73.66 58.42 180)
		(effects
			(font
				(size 1.27 1.27)
			)
			(justify right bottom)
		)
	)
	(label "CC2"
		(at 110.49 111.76 180)
		(effects
			(font
				(size 1.27 1.27)
			)
			(justify right bottom)
		)
	)
	(label "SCL"
		(at 158.75 167.64 180)
		(effects
			(font
				(size 1.27 1.27)
			)
			(justify right bottom)
		)
	)
	(label "SDA"
		(at 205.74 81.28 0)
		(effects
			(font
				(size 1.27 1.27)
			)
			(justify left bottom)
		)
	)
	(label "SCL"
		(at 205.74 78.74 0)
		(effects
			(font
				(size 1.27 1.27)
			)
			(justify left bottom)
		)
	)
	(label "VBUS_DISCH"
		(at 261.62 53.34 180)
		(effects
			(font
				(size 1.27 1.27)
			)
			(justify right bottom)
		)
	)
	(label "CC1"
		(at 110.49 95.25 180)
		(effects
			(font
				(size 1.27 1.27)
			)
			(justify right bottom)
		)
	)
	(label "CC2"
		(at 73.66 60.96 180)
		(effects
			(font
				(size 1.27 1.27)
			)
			(justify right bottom)
		)
	)
	(label "VBUS_DISCH"
		(at 172.72 83.82 180)
		(effects
			(font
				(size 1.27 1.27)
			)
			(justify right bottom)
		)
	)
	(label "VBUS_EN"
		(at 261.62 50.8 180)
		(effects
			(font
				(size 1.27 1.27)
			)
			(justify right bottom)
		)
	)
	(label "VBUS_EN"
		(at 280.67 83.82 0)
		(effects
			(font
				(size 1.27 1.27)
			)
			(justify left bottom)
		)
	)
	(label "SDA"
		(at 158.75 170.18 180)
		(effects
			(font
				(size 1.27 1.27)
			)
			(justify right bottom)
		)
	)
	(label "SDA"
		(at 186.69 137.16 180)
		(effects
			(font
				(size 1.27 1.27)
			)
			(justify right bottom)
		)
	)
	(label "CC2"
		(at 205.74 71.12 0)
		(effects
			(font
				(size 1.27 1.27)
			)
			(justify left bottom)
		)
	)
	(label "QWIIC_VCC"
		(at 152.4 134.62 0)
		(effects
			(font
				(size 1.27 1.27)
			)
			(justify left bottom)
		)
	)
	(label "SCL"
		(at 186.69 139.7 180)
		(effects
			(font
				(size 1.27 1.27)
			)
			(justify right bottom)
		)
	)
	(label "QWIIC_VCC"
		(at 158.75 172.72 180)
		(effects
			(font
				(size 1.27 1.27)
			)
			(justify right bottom)
		)
	)
	(label "CC1"
		(at 205.74 68.58 0)
		(effects
			(font
				(size 1.27 1.27)
			)
			(justify left bottom)
		)
	)
	(global_label "POWER_OK3"
		(shape input)
		(at 255.27 71.12 0)
		(fields_autoplaced yes)
		(effects
			(font
				(size 1.27 1.27)
			)
			(justify left)
		)
		(property "Intersheetrefs" "${INTERSHEET_REFS}"
			(at 269.5037 71.12 0)
			(effects
				(font
					(size 1.27 1.27)
				)
				(justify left)
				(hide yes)
			)
		)
	)
	(global_label "POWER_OK3"
		(shape input)
		(at 261.62 148.59 0)
		(fields_autoplaced yes)
		(effects
			(font
				(size 1.27 1.27)
			)
			(justify left)
		)
		(property "Intersheetrefs" "${INTERSHEET_REFS}"
			(at 275.8537 148.59 0)
			(effects
				(font
					(size 1.27 1.27)
				)
				(justify left)
				(hide yes)
			)
		)
	)
	(global_label "POWER_OK2"
		(shape input)
		(at 255.27 68.58 0)
		(fields_autoplaced yes)
		(effects
			(font
				(size 1.27 1.27)
			)
			(justify left)
		)
		(property "Intersheetrefs" "${INTERSHEET_REFS}"
			(at 269.5037 68.58 0)
			(effects
				(font
					(size 1.27 1.27)
				)
				(justify left)
				(hide yes)
			)
		)
	)
	(global_label "POWER_OK2"
		(shape input)
		(at 242.57 148.59 0)
		(fields_autoplaced yes)
		(effects
			(font
				(size 1.27 1.27)
			)
			(justify left)
		)
		(property "Intersheetrefs" "${INTERSHEET_REFS}"
			(at 256.8037 148.59 0)
			(effects
				(font
					(size 1.27 1.27)
				)
				(justify left)
				(hide yes)
			)
		)
	)
	(symbol
		(lib_id "antmicropower:GND")
		(at 212.09 62.23 0)
		(unit 1)
		(exclude_from_sim no)
		(in_bom yes)
		(on_board yes)
		(dnp no)
		(property "Reference" "#PWR088"
			(at 220.98 64.77 0)
			(effects
				(font
					(size 1.27 1.27)
					(thickness 0.15)
				)
				(justify left bottom)
				(hide yes)
			)
		)
		(property "Value" "GND"
			(at 212.09 66.04 0)
			(effects
				(font
					(size 1.27 1.27)
					(thickness 0.15)
				)
			)
		)
		(property "Footprint" ""
			(at 220.98 69.85 0)
			(effects
				(font
					(size 1.27 1.27)
					(thickness 0.15)
				)
				(justify left bottom)
				(hide yes)
			)
		)
		(property "Datasheet" ""
			(at 220.98 74.93 0)
			(effects
				(font
					(size 1.27 1.27)
					(thickness 0.15)
				)
				(justify left bottom)
				(hide yes)
			)
		)
		(property "Description" ""
			(at 212.09 62.23 0)
			(effects
				(font
					(size 1.27 1.27)
				)
				(hide yes)
			)
		)
		(property "Author" "Antmicro"
			(at 220.98 69.85 0)
			(effects
				(font
					(size 1.27 1.27)
					(thickness 0.15)
				)
				(justify left bottom)
				(hide yes)
			)
		)
		(property "License" "Apache-2.0"
			(at 220.98 72.39 0)
			(effects
				(font
					(size 1.27 1.27)
					(thickness 0.15)
				)
				(justify left bottom)
				(hide yes)
			)
		)
		(pin "1"
		)
		(instances
			(project "usb-c-power-adapter"
				(path ""
					(reference "#PWR088")
					(unit 1)
				)
			)
		)
	)
	(symbol
		(lib_id "antmicroResistors0402:R_1k2_0402")
		(at 222.25 135.89 90)
		(unit 1)
		(exclude_from_sim no)
		(in_bom yes)
		(on_board yes)
		(dnp no)
		(fields_autoplaced yes)
		(property "Reference" "R34"
			(at 224.79 132.08 90)
			(effects
				(font
					(size 1.27 1.27)
					(thickness 0.15)
				)
				(justify right)
			)
		)
		(property "Value" "R_1k2_0402"
			(at 234.95 115.57 0)
			(effects
				(font
					(size 1.27 1.27)
					(thickness 0.15)
				)
				(justify left bottom)
				(hide yes)
			)
		)
		(property "Footprint" "antmicro-footprints:R_0402_1005Metric"
			(at 237.49 115.57 0)
			(effects
				(font
					(size 1.27 1.27)
					(thickness 0.15)
				)
				(justify left bottom)
				(hide yes)
			)
		)
		(property "Datasheet" "https://www.bourns.com/docs/product-datasheets/cr.pdf"
			(at 240.03 115.57 0)
			(effects
				(font
					(size 1.27 1.27)
					(thickness 0.15)
				)
				(justify left bottom)
				(hide yes)
			)
		)
		(property "Description" "SMD Chip Resistor, 1.2 kohm, ± 1%, 62.5 mW, 0402 [1005 Metric], Thick Film, General Purpose"
			(at 222.25 135.89 0)
			(effects
				(font
					(size 1.27 1.27)
				)
				(hide yes)
			)
		)
		(property "MPN" "CR0402-FX-1201GLF"
			(at 242.57 115.57 0)
			(effects
				(font
					(size 1.27 1.27)
					(thickness 0.15)
				)
				(justify left bottom)
				(hide yes)
			)
		)
		(property "Manufacturer" "Bourns"
			(at 245.11 115.57 0)
			(effects
				(font
					(size 1.27 1.27)
					(thickness 0.15)
				)
				(justify left bottom)
				(hide yes)
			)
		)
		(property "License" "Apache-2.0"
			(at 247.65 115.57 0)
			(effects
				(font
					(size 1.27 1.27)
					(thickness 0.15)
				)
				(justify left bottom)
				(hide yes)
			)
		)
		(property "Author" "Antmicro"
			(at 250.19 115.57 0)
			(effects
				(font
					(size 1.27 1.27)
					(thickness 0.15)
				)
				(justify left bottom)
				(hide yes)
			)
		)
		(property "Val" "1k2"
			(at 224.79 134.62 90)
			(effects
				(font
					(size 1.27 1.27)
					(thickness 0.15)
				)
				(justify right)
			)
		)
		(property "Tolerance" "1%"
			(at 232.41 115.57 0)
			(effects
				(font
					(size 1.27 1.27)
				)
				(justify left bottom)
				(hide yes)
			)
		)
		(pin "2"
		)
		(pin "1"
		)
		(instances
			(project "usb-c-power-adapter"
				(path ""
					(reference "R34")
					(unit 1)
				)
			)
		)
	)
	(symbol
		(lib_id "antmicroResistors0402:R_4k7_0402")
		(at 171.45 132.08 90)
		(unit 1)
		(exclude_from_sim no)
		(in_bom no)
		(on_board yes)
		(dnp yes)
		(fields_autoplaced yes)
		(property "Reference" "R31"
			(at 173.99 128.27 90)
			(effects
				(font
					(size 1.27 1.27)
					(thickness 0.15)
				)
				(justify right)
			)
		)
		(property "Value" "R_4k7_0402"
			(at 184.15 111.76 0)
			(effects
				(font
					(size 1.27 1.27)
					(thickness 0.15)
				)
				(justify left bottom)
				(hide yes)
			)
		)
		(property "Footprint" "antmicro-footprints:R_0402_1005Metric"
			(at 186.69 111.76 0)
			(effects
				(font
					(size 1.27 1.27)
					(thickness 0.15)
				)
				(justify left bottom)
				(hide yes)
			)
		)
		(property "Datasheet" "https://www.bourns.com/docs/product-datasheets/cr.pdf"
			(at 189.23 111.76 0)
			(effects
				(font
					(size 1.27 1.27)
					(thickness 0.15)
				)
				(justify left bottom)
				(hide yes)
			)
		)
		(property "Description" "SMD Chip Resistor, 4.7 kohm, ± 1%, 62.5 mW, 0402 [1005 Metric], Thick Film, General Purpose"
			(at 171.45 132.08 0)
			(effects
				(font
					(size 1.27 1.27)
				)
				(hide yes)
			)
		)
		(property "MPN" "CR0402-FX-4701GLF"
			(at 191.77 111.76 0)
			(effects
				(font
					(size 1.27 1.27)
					(thickness 0.15)
				)
				(justify left bottom)
				(hide yes)
			)
		)
		(property "Manufacturer" "Bourns"
			(at 194.31 111.76 0)
			(effects
				(font
					(size 1.27 1.27)
					(thickness 0.15)
				)
				(justify left bottom)
				(hide yes)
			)
		)
		(property "License" "Apache-2.0"
			(at 196.85 111.76 0)
			(effects
				(font
					(size 1.27 1.27)
					(thickness 0.15)
				)
				(justify left bottom)
				(hide yes)
			)
		)
		(property "Author" "Antmicro"
			(at 199.39 111.76 0)
			(effects
				(font
					(size 1.27 1.27)
					(thickness 0.15)
				)
				(justify left bottom)
				(hide yes)
			)
		)
		(property "Val" "4k7"
			(at 173.99 130.81 90)
			(effects
				(font
					(size 1.27 1.27)
					(thickness 0.15)
				)
				(justify right)
			)
		)
		(property "Tolerance" "1%"
			(at 181.61 111.76 0)
			(effects
				(font
					(size 1.27 1.27)
				)
				(justify left bottom)
				(hide yes)
			)
		)
		(pin "2"
		)
		(pin "1"
		)
		(instances
			(project "usb-c-power-adapter"
				(path ""
					(reference "R31")
					(unit 1)
				)
			)
		)
	)
	(symbol
		(lib_id "antmicroTestPoints:TP_0.75mm_SMD")
		(at 252.73 58.42 0)
		(unit 1)
		(exclude_from_sim no)
		(in_bom no)
		(on_board yes)
		(dnp no)
		(fields_autoplaced yes)
		(property "Reference" "TP12"
			(at 257.81 58.42 0)
			(effects
				(font
					(size 1.27 1.27)
					(thickness 0.15)
				)
				(justify left)
			)
		)
		(property "Value" "TP_0.75mm_SMD"
			(at 263.525 62.23 0)
			(effects
				(font
					(size 1.27 1.27)
					(thickness 0.15)
				)
				(justify left bottom)
				(hide yes)
			)
		)
		(property "Footprint" "antmicro-footprints:TP_SMD_0.75mm"
			(at 263.525 64.77 0)
			(effects
				(font
					(size 1.27 1.27)
					(thickness 0.15)
				)
				(justify left bottom)
				(hide yes)
			)
		)
		(property "Datasheet" ""
			(at 270.51 71.12 0)
			(effects
				(font
					(size 1.27 1.27)
					(thickness 0.15)
				)
				(justify left bottom)
				(hide yes)
			)
		)
		(property "Description" "SMT test point"
			(at 252.73 58.42 0)
			(effects
				(font
					(size 1.27 1.27)
				)
				(hide yes)
			)
		)
		(property "MPN" ""
			(at 263.525 69.85 0)
			(effects
				(font
					(size 1.27 1.27)
					(thickness 0.15)
				)
				(justify left bottom)
				(hide yes)
			)
		)
		(property "Manufacturer" ""
			(at 263.525 64.77 0)
			(effects
				(font
					(size 1.27 1.27)
					(thickness 0.15)
				)
				(justify left bottom)
				(hide yes)
			)
		)
		(property "Author" "Antmicro"
			(at 263.525 67.31 0)
			(effects
				(font
					(size 1.27 1.27)
					(thickness 0.15)
				)
				(justify left bottom)
				(hide yes)
			)
		)
		(property "License" "Apache-2.0"
			(at 263.525 69.85 0)
			(effects
				(font
					(size 1.27 1.27)
					(thickness 0.15)
				)
				(justify left bottom)
				(hide yes)
			)
		)
		(pin "1"
		)
		(instances
			(project "usb-c-power-adapter"
				(path ""
					(reference "TP12")
					(unit 1)
				)
			)
		)
	)
	(symbol
		(lib_id "antmicropower:GND")
		(at 260.35 92.71 0)
		(mirror y)
		(unit 1)
		(exclude_from_sim no)
		(in_bom yes)
		(on_board yes)
		(dnp no)
		(fields_autoplaced yes)
		(property "Reference" "#PWR080"
			(at 251.46 95.25 0)
			(effects
				(font
					(size 1.27 1.27)
					(thickness 0.15)
				)
				(justify left bottom)
				(hide yes)
			)
		)
		(property "Value" "GND"
			(at 260.35 97.155 0)
			(effects
				(font
					(size 1.27 1.27)
					(thickness 0.15)
				)
			)
		)
		(property "Footprint" ""
			(at 251.46 100.33 0)
			(effects
				(font
					(size 1.27 1.27)
					(thickness 0.15)
				)
				(justify left bottom)
				(hide yes)
			)
		)
		(property "Datasheet" ""
			(at 251.46 105.41 0)
			(effects
				(font
					(size 1.27 1.27)
					(thickness 0.15)
				)
				(justify left bottom)
				(hide yes)
			)
		)
		(property "Description" ""
			(at 260.35 92.71 0)
			(effects
				(font
					(size 1.27 1.27)
				)
				(hide yes)
			)
		)
		(property "Author" "Antmicro"
			(at 251.46 100.33 0)
			(effects
				(font
					(size 1.27 1.27)
					(thickness 0.15)
				)
				(justify left bottom)
				(hide yes)
			)
		)
		(property "License" "Apache-2.0"
			(at 251.46 102.87 0)
			(effects
				(font
					(size 1.27 1.27)
					(thickness 0.15)
				)
				(justify left bottom)
				(hide yes)
			)
		)
		(pin "1"
		)
		(instances
			(project "usb-c-power-adapter"
				(path ""
					(reference "#PWR080")
					(unit 1)
				)
			)
		)
	)
	(symbol
		(lib_id "antmicroResistors0402:R_10k_0402")
		(at 198.12 62.23 270)
		(unit 1)
		(exclude_from_sim no)
		(in_bom yes)
		(on_board yes)
		(dnp no)
		(fields_autoplaced yes)
		(property "Reference" "R4"
			(at 200.66 63.5 90)
			(effects
				(font
					(size 1.27 1.27)
					(thickness 0.15)
				)
				(justify left)
			)
		)
		(property "Value" "R_10k_0402"
			(at 185.42 82.55 0)
			(effects
				(font
					(size 1.27 1.27)
					(thickness 0.15)
				)
				(justify left bottom)
				(hide yes)
			)
		)
		(property "Footprint" "antmicro-footprints:R_0402_1005Metric"
			(at 182.88 82.55 0)
			(effects
				(font
					(size 1.27 1.27)
					(thickness 0.15)
				)
				(justify left bottom)
				(hide yes)
			)
		)
		(property "Datasheet" "https://www.bourns.com/docs/product-datasheets/cr.pdf"
			(at 180.34 82.55 0)
			(effects
				(font
					(size 1.27 1.27)
					(thickness 0.15)
				)
				(justify left bottom)
				(hide yes)
			)
		)
		(property "Description" "SMD Chip Resistor, 10 kohm, ± 1%, 62.5 mW, 0402 [1005 Metric], Thick Film, General Purpose"
			(at 198.12 62.23 0)
			(effects
				(font
					(size 1.27 1.27)
				)
				(hide yes)
			)
		)
		(property "MPN" "CR0402-FX-1002GLF"
			(at 177.8 82.55 0)
			(effects
				(font
					(size 1.27 1.27)
					(thickness 0.15)
				)
				(justify left bottom)
				(hide yes)
			)
		)
		(property "Manufacturer" "Bourns"
			(at 175.26 82.55 0)
			(effects
				(font
					(size 1.27 1.27)
					(thickness 0.15)
				)
				(justify left bottom)
				(hide yes)
			)
		)
		(property "License" "Apache-2.0"
			(at 172.72 82.55 0)
			(effects
				(font
					(size 1.27 1.27)
					(thickness 0.15)
				)
				(justify left bottom)
				(hide yes)
			)
		)
		(property "Author" "Antmicro"
			(at 170.18 82.55 0)
			(effects
				(font
					(size 1.27 1.27)
					(thickness 0.15)
				)
				(justify left bottom)
				(hide yes)
			)
		)
		(property "Val" "10k"
			(at 200.66 66.04 90)
			(effects
				(font
					(size 1.27 1.27)
					(thickness 0.15)
				)
				(justify left)
			)
		)
		(property "Tolerance" "1%"
			(at 187.96 82.55 0)
			(effects
				(font
					(size 1.27 1.27)
				)
				(justify left bottom)
				(hide yes)
			)
		)
		(pin "1"
		)
		(pin "2"
		)
		(instances
			(project "usb-c-power-adapter"
				(path ""
					(reference "R4")
					(unit 1)
				)
			)
		)
	)
	(symbol
		(lib_id "antmicropower:GND")
		(at 215.9 91.44 0)
		(unit 1)
		(exclude_from_sim no)
		(in_bom yes)
		(on_board yes)
		(dnp no)
		(property "Reference" "#PWR082"
			(at 224.79 93.98 0)
			(effects
				(font
					(size 1.27 1.27)
					(thickness 0.15)
				)
				(justify left bottom)
				(hide yes)
			)
		)
		(property "Value" "GND"
			(at 215.9 95.885 0)
			(effects
				(font
					(size 1.27 1.27)
					(thickness 0.15)
				)
			)
		)
		(property "Footprint" ""
			(at 224.79 99.06 0)
			(effects
				(font
					(size 1.27 1.27)
					(thickness 0.15)
				)
				(justify left bottom)
				(hide yes)
			)
		)
		(property "Datasheet" ""
			(at 224.79 104.14 0)
			(effects
				(font
					(size 1.27 1.27)
					(thickness 0.15)
				)
				(justify left bottom)
				(hide yes)
			)
		)
		(property "Description" ""
			(at 215.9 91.44 0)
			(effects
				(font
					(size 1.27 1.27)
				)
				(hide yes)
			)
		)
		(property "Author" "Antmicro"
			(at 224.79 99.06 0)
			(effects
				(font
					(size 1.27 1.27)
					(thickness 0.15)
				)
				(justify left bottom)
				(hide yes)
			)
		)
		(property "License" "Apache-2.0"
			(at 224.79 101.6 0)
			(effects
				(font
					(size 1.27 1.27)
					(thickness 0.15)
				)
				(justify left bottom)
				(hide yes)
			)
		)
		(pin "1"
		)
		(instances
			(project "usb-c-power-adapter"
				(path ""
					(reference "#PWR082")
					(unit 1)
				)
			)
		)
	)
	(symbol
		(lib_id "antmicropower:GND")
		(at 149.86 176.53 0)
		(unit 1)
		(exclude_from_sim no)
		(in_bom yes)
		(on_board yes)
		(dnp no)
		(fields_autoplaced yes)
		(property "Reference" "#PWR051"
			(at 158.75 179.07 0)
			(effects
				(font
					(size 1.27 1.27)
					(thickness 0.15)
				)
				(justify left bottom)
				(hide yes)
			)
		)
		(property "Value" "GND"
			(at 149.86 180.975 0)
			(effects
				(font
					(size 1.27 1.27)
					(thickness 0.15)
				)
			)
		)
		(property "Footprint" ""
			(at 158.75 184.15 0)
			(effects
				(font
					(size 1.27 1.27)
					(thickness 0.15)
				)
				(justify left bottom)
				(hide yes)
			)
		)
		(property "Datasheet" ""
			(at 158.75 189.23 0)
			(effects
				(font
					(size 1.27 1.27)
					(thickness 0.15)
				)
				(justify left bottom)
				(hide yes)
			)
		)
		(property "Description" ""
			(at 149.86 176.53 0)
			(effects
				(font
					(size 1.27 1.27)
				)
				(hide yes)
			)
		)
		(property "Author" "Antmicro"
			(at 158.75 184.15 0)
			(effects
				(font
					(size 1.27 1.27)
					(thickness 0.15)
				)
				(justify left bottom)
				(hide yes)
			)
		)
		(property "License" "Apache-2.0"
			(at 158.75 186.69 0)
			(effects
				(font
					(size 1.27 1.27)
					(thickness 0.15)
				)
				(justify left bottom)
				(hide yes)
			)
		)
		(pin "1"
		)
		(instances
			(project "usb-c-power-adapter"
				(path ""
					(reference "#PWR051")
					(unit 1)
				)
			)
		)
	)
	(symbol
		(lib_id "antmicropower:VCC")
		(at 186.69 46.99 0)
		(mirror y)
		(unit 1)
		(exclude_from_sim no)
		(in_bom yes)
		(on_board yes)
		(dnp no)
		(fields_autoplaced yes)
		(property "Reference" "#PWR083"
			(at 186.69 50.8 0)
			(effects
				(font
					(size 1.27 1.27)
				)
				(hide yes)
			)
		)
		(property "Value" "VCC"
			(at 186.69 43.18 0)
			(effects
				(font
					(size 1.27 1.27)
				)
			)
		)
		(property "Footprint" ""
			(at 186.69 46.99 0)
			(effects
				(font
					(size 1.27 1.27)
				)
				(hide yes)
			)
		)
		(property "Datasheet" ""
			(at 186.69 46.99 0)
			(effects
				(font
					(size 1.27 1.27)
				)
				(hide yes)
			)
		)
		(property "Description" ""
			(at 186.69 46.99 0)
			(effects
				(font
					(size 1.27 1.27)
				)
				(hide yes)
			)
		)
		(pin "1"
		)
		(instances
			(project "usb-c-power-adapter"
				(path ""
					(reference "#PWR083")
					(unit 1)
				)
			)
		)
	)
	(symbol
		(lib_id "antmicroResistors0402:R_470R_0402")
		(at 156.21 69.85 90)
		(unit 1)
		(exclude_from_sim no)
		(in_bom yes)
		(on_board yes)
		(dnp no)
		(fields_autoplaced yes)
		(property "Reference" "R19"
			(at 158.75 66.04 90)
			(effects
				(font
					(size 1.27 1.27)
					(thickness 0.15)
				)
				(justify right)
			)
		)
		(property "Value" "R_470R_0402"
			(at 168.91 49.53 0)
			(effects
				(font
					(size 1.27 1.27)
					(thickness 0.15)
				)
				(justify left bottom)
				(hide yes)
			)
		)
		(property "Footprint" "antmicro-footprints:R_0402_1005Metric"
			(at 171.45 49.53 0)
			(effects
				(font
					(size 1.27 1.27)
					(thickness 0.15)
				)
				(justify left bottom)
				(hide yes)
			)
		)
		(property "Datasheet" "https://www.bourns.com/docs/product-datasheets/cr.pdf"
			(at 173.99 49.53 0)
			(effects
				(font
					(size 1.27 1.27)
					(thickness 0.15)
				)
				(justify left bottom)
				(hide yes)
			)
		)
		(property "Description" "SMD Chip Resistor, 470 ohm, ± 1%, 62.5 mW, 0402 [1005 Metric], Thick Film, General Purpose"
			(at 156.21 69.85 0)
			(effects
				(font
					(size 1.27 1.27)
				)
				(hide yes)
			)
		)
		(property "MPN" "CR0402-FX-4700GLF"
			(at 176.53 49.53 0)
			(effects
				(font
					(size 1.27 1.27)
					(thickness 0.15)
				)
				(justify left bottom)
				(hide yes)
			)
		)
		(property "Manufacturer" "Bourns"
			(at 179.07 49.53 0)
			(effects
				(font
					(size 1.27 1.27)
					(thickness 0.15)
				)
				(justify left bottom)
				(hide yes)
			)
		)
		(property "License" "Apache-2.0"
			(at 181.61 49.53 0)
			(effects
				(font
					(size 1.27 1.27)
					(thickness 0.15)
				)
				(justify left bottom)
				(hide yes)
			)
		)
		(property "Author" "Antmicro"
			(at 184.15 49.53 0)
			(effects
				(font
					(size 1.27 1.27)
					(thickness 0.15)
				)
				(justify left bottom)
				(hide yes)
			)
		)
		(property "Val" "470R"
			(at 158.75 68.58 90)
			(effects
				(font
					(size 1.27 1.27)
					(thickness 0.15)
				)
				(justify right)
			)
		)
		(property "Tolerance" "1%"
			(at 166.37 49.53 0)
			(effects
				(font
					(size 1.27 1.27)
				)
				(justify left bottom)
				(hide yes)
			)
		)
		(pin "1"
		)
		(pin "2"
		)
		(instances
			(project "usb-c-power-adapter"
				(path ""
					(reference "R19")
					(unit 1)
				)
			)
		)
	)
	(symbol
		(lib_id "antmicroTVSDiodes:TVS2200DRVR")
		(at 99.06 80.01 0)
		(mirror y)
		(unit 1)
		(exclude_from_sim no)
		(in_bom yes)
		(on_board yes)
		(dnp no)
		(fields_autoplaced yes)
		(property "Reference" "U5"
			(at 93.98 72.39 0)
			(effects
				(font
					(size 1.27 1.27)
				)
			)
		)
		(property "Value" "TVS2200DRVR"
			(at 96.52 76.2 0)
			(effects
				(font
					(size 1.27 1.27)
				)
				(justify left)
				(hide yes)
			)
		)
		(property "Footprint" "antmicro-footprints:WSON-6-1EP_2x2mm_P0.65mm"
			(at 97.79 79.99 0)
			(effects
				(font
					(size 1.27 1.27)
				)
				(justify left bottom)
				(hide yes)
			)
		)
		(property "Datasheet" "https://www.ti.com/lit/ds/symlink/tvs2200.pdf?ts=1712230685180&ref_url=https%253A%252F%252Fwww.ti.com%252Fproduct%252FTVS2200"
			(at 97.79 82.99 0)
			(effects
				(font
					(size 1.27 1.27)
				)
				(justify left bottom)
				(hide yes)
			)
		)
		(property "Description" "ESD Protection Device, 1 kV, WSON-6, 22 V, 105 pF"
			(at 99.06 80.01 0)
			(effects
				(font
					(size 1.27 1.27)
				)
				(hide yes)
			)
		)
		(property "MPN" "TVS2200DRVR"
			(at 93.98 74.93 0)
			(effects
				(font
					(size 1.27 1.27)
				)
			)
		)
		(property "Manufacturer" "Texas Instruments"
			(at 97.79 88.9 0)
			(effects
				(font
					(size 1.27 1.27)
				)
				(justify left bottom)
				(hide yes)
			)
		)
		(property "License" "Apache-2.0"
			(at 97.79 93.98 0)
			(effects
				(font
					(size 1.27 1.27)
				)
				(justify left bottom)
				(hide yes)
			)
		)
		(property "Author" "Antmicro"
			(at 97.79 91.44 0)
			(effects
				(font
					(size 1.27 1.27)
				)
				(justify left bottom)
				(hide yes)
			)
		)
		(pin "2"
		)
		(pin "3"
		)
		(pin "4"
		)
		(pin "6"
		)
		(pin "1"
		)
		(pin "7"
		)
		(pin "5"
		)
		(instances
			(project "usb-c-power-adapter"
				(path ""
					(reference "U5")
					(unit 1)
				)
			)
		)
	)
	(symbol
		(lib_id "antmicropower:GND")
		(at 198.12 68.58 0)
		(unit 1)
		(exclude_from_sim no)
		(in_bom yes)
		(on_board yes)
		(dnp no)
		(property "Reference" "#PWR087"
			(at 207.01 71.12 0)
			(effects
				(font
					(size 1.27 1.27)
					(thickness 0.15)
				)
				(justify left bottom)
				(hide yes)
			)
		)
		(property "Value" "GND"
			(at 198.12 72.39 0)
			(effects
				(font
					(size 1.27 1.27)
					(thickness 0.15)
				)
			)
		)
		(property "Footprint" ""
			(at 207.01 76.2 0)
			(effects
				(font
					(size 1.27 1.27)
					(thickness 0.15)
				)
				(justify left bottom)
				(hide yes)
			)
		)
		(property "Datasheet" ""
			(at 207.01 81.28 0)
			(effects
				(font
					(size 1.27 1.27)
					(thickness 0.15)
				)
				(justify left bottom)
				(hide yes)
			)
		)
		(property "Description" ""
			(at 198.12 68.58 0)
			(effects
				(font
					(size 1.27 1.27)
				)
				(hide yes)
			)
		)
		(property "Author" "Antmicro"
			(at 207.01 76.2 0)
			(effects
				(font
					(size 1.27 1.27)
					(thickness 0.15)
				)
				(justify left bottom)
				(hide yes)
			)
		)
		(property "License" "Apache-2.0"
			(at 207.01 78.74 0)
			(effects
				(font
					(size 1.27 1.27)
					(thickness 0.15)
				)
				(justify left bottom)
				(hide yes)
			)
		)
		(pin "1"
		)
		(instances
			(project "usb-c-power-adapter"
				(path ""
					(reference "#PWR087")
					(unit 1)
				)
			)
		)
	)
	(symbol
		(lib_id "antmicroMechanicalParts:MP_Pad3.5mm_Drill2.2mm")
		(at 215.9 175.26 0)
		(unit 1)
		(exclude_from_sim no)
		(in_bom no)
		(on_board yes)
		(dnp no)
		(fields_autoplaced yes)
		(property "Reference" "MP1"
			(at 224.79 173.99 0)
			(effects
				(font
					(size 1.27 1.27)
					(thickness 0.15)
				)
				(justify left)
			)
		)
		(property "Value" "MP_Pad3.5mm_Drill2.2mm"
			(at 224.79 176.53 0)
			(effects
				(font
					(size 1.27 1.27)
					(thickness 0.15)
				)
				(justify left)
			)
		)
		(property "Footprint" "antmicro-footprints:MP_Pad3.5mm_Drill2.2mm"
			(at 231.14 185.42 0)
			(effects
				(font
					(size 1.27 1.27)
					(thickness 0.15)
				)
				(justify left bottom)
				(hide yes)
			)
		)
		(property "Datasheet" ""
			(at 232.74 190.83 0)
			(effects
				(font
					(size 1.27 1.27)
					(thickness 0.15)
				)
				(justify left bottom)
				(hide yes)
			)
		)
		(property "Description" "PCB mounting point"
			(at 215.9 175.26 0)
			(effects
				(font
					(size 1.27 1.27)
				)
				(hide yes)
			)
		)
		(property "Author" "Antmicro"
			(at 231.14 190.5 0)
			(effects
				(font
					(size 1.27 1.27)
					(thickness 0.15)
				)
				(justify left bottom)
				(hide yes)
			)
		)
		(property "License" "Apache-2.0"
			(at 231.14 193.04 0)
			(effects
				(font
					(size 1.27 1.27)
					(thickness 0.15)
				)
				(justify left bottom)
				(hide yes)
			)
		)
		(pin "1"
		)
		(instances
			(project "usb-c-power-adapter"
				(path ""
					(reference "MP1")
					(unit 1)
				)
			)
		)
	)
	(symbol
		(lib_id "antmicroUSBConnectors:USB-C_GCT_USB4105-GF-A")
		(at 66.04 53.34 0)
		(unit 1)
		(exclude_from_sim no)
		(in_bom yes)
		(on_board yes)
		(dnp no)
		(fields_autoplaced yes)
		(property "Reference" "J1"
			(at 52.705 45.72 0)
			(effects
				(font
					(size 1.27 1.27)
					(thickness 0.15)
				)
			)
		)
		(property "Value" "USB-C_GCT_USB4105-GF-A"
			(at 52.705 48.26 0)
			(effects
				(font
					(size 1.27 1.27)
					(thickness 0.15)
				)
			)
		)
		(property "Footprint" "antmicro-footprints:USB-C_Receptacle_GCT_USB4105-GF-A"
			(at 104.14 60.96 0)
			(effects
				(font
					(size 1.27 1.27)
					(thickness 0.15)
				)
				(justify left bottom)
				(hide yes)
			)
		)
		(property "Datasheet" "https://gct.co/files/drawings/usb4105.pdf"
			(at 104.14 63.5 0)
			(effects
				(font
					(size 1.27 1.27)
					(thickness 0.15)
				)
				(justify left bottom)
				(hide yes)
			)
		)
		(property "Description" "USB-C (USB TYPE-C) USB 2.0 Receptacle Connector 24 (16+8 Dummy) Position Surface Mount, Right Angle"
			(at 66.04 53.34 0)
			(effects
				(font
					(size 1.27 1.27)
				)
				(hide yes)
			)
		)
		(property "Manufacturer" "GCT"
			(at 104.14 66.04 0)
			(effects
				(font
					(size 1.27 1.27)
					(thickness 0.15)
				)
				(justify left bottom)
				(hide yes)
			)
		)
		(property "MPN" "USB4105-GF-A"
			(at 104.14 68.58 0)
			(effects
				(font
					(size 1.27 1.27)
					(thickness 0.15)
				)
				(justify left bottom)
				(hide yes)
			)
		)
		(property "Author" "Antmicro"
			(at 104.14 71.12 0)
			(effects
				(font
					(size 1.27 1.27)
					(thickness 0.15)
				)
				(justify left bottom)
				(hide yes)
			)
		)
		(property "License" "Apache-2.0"
			(at 104.14 73.66 0)
			(effects
				(font
					(size 1.27 1.27)
					(thickness 0.15)
				)
				(justify left bottom)
				(hide yes)
			)
		)
		(pin "B6"
		)
		(pin "A8"
		)
		(pin "A9"
		)
		(pin "B1"
		)
		(pin "B12"
		)
		(pin "B7"
		)
		(pin "B9"
		)
		(pin "A7"
		)
		(pin "A5"
		)
		(pin "B4"
		)
		(pin "A6"
		)
		(pin "B5"
		)
		(pin "A4"
		)
		(pin "A12"
		)
		(pin "A1"
		)
		(pin "B8"
		)
		(pin "SH"
		)
		(instances
			(project "usb-c-power-adapter"
				(path ""
					(reference "J1")
					(unit 1)
				)
			)
		)
	)
	(symbol
		(lib_id "antmicroTransistorsFETsMOSFETsSingle:SQS401EN-T1_BE3")
		(at 304.8 67.31 270)
		(mirror x)
		(unit 1)
		(exclude_from_sim no)
		(in_bom yes)
		(on_board yes)
		(dnp no)
		(fields_autoplaced yes)
		(property "Reference" "Q1"
			(at 307.34 54.61 90)
			(effects
				(font
					(size 1.27 1.27)
					(thickness 0.15)
				)
			)
		)
		(property "Value" "SQS401EN-T1_BE3"
			(at 294.64 52.07 0)
			(effects
				(font
					(size 1.27 1.27)
					(thickness 0.15)
				)
				(justify left bottom)
				(hide yes)
			)
		)
		(property "Footprint" "antmicro-footprints:Vishay_PowerPAK_1212-8_Single"
			(at 292.1 52.07 0)
			(effects
				(font
					(size 1.27 1.27)
					(thickness 0.15)
				)
				(justify left bottom)
				(hide yes)
			)
		)
		(property "Datasheet" "https://www.vishay.com/docs/65529/sqs401en.pdf"
			(at 289.56 52.07 0)
			(effects
				(font
					(size 1.27 1.27)
					(thickness 0.15)
				)
				(justify left bottom)
				(hide yes)
			)
		)
		(property "Description" "MOSFET, P Channel, 40 V, 16A, 0.047 ohm, PowerPAK 1212-8, Surface Mount"
			(at 304.8 67.31 0)
			(effects
				(font
					(size 1.27 1.27)
				)
				(hide yes)
			)
		)
		(property "MPN" "SQS401EN-T1_BE3"
			(at 307.34 57.15 90)
			(effects
				(font
					(size 1.27 1.27)
					(thickness 0.15)
				)
			)
		)
		(property "Manufacturer" "Vishay"
			(at 287.02 52.07 0)
			(effects
				(font
					(size 1.27 1.27)
					(thickness 0.15)
				)
				(justify left bottom)
				(hide yes)
			)
		)
		(property "Author" "Antmicro"
			(at 284.48 52.07 0)
			(effects
				(font
					(size 1.27 1.27)
					(thickness 0.15)
				)
				(justify left bottom)
				(hide yes)
			)
		)
		(property "License" "Apache-2.0"
			(at 281.94 52.07 0)
			(effects
				(font
					(size 1.27 1.27)
					(thickness 0.15)
				)
				(justify left bottom)
				(hide yes)
			)
		)
		(pin "4"
		)
		(pin "1"
		)
		(pin "3"
		)
		(pin "5"
		)
		(pin "2"
		)
		(instances
			(project "usb-c-power-adapter"
				(path ""
					(reference "Q1")
					(unit 1)
				)
			)
		)
	)
	(symbol
		(lib_id "antmicropower:GND")
		(at 146.05 83.82 0)
		(mirror y)
		(unit 1)
		(exclude_from_sim no)
		(in_bom yes)
		(on_board yes)
		(dnp no)
		(fields_autoplaced yes)
		(property "Reference" "#PWR018"
			(at 137.16 86.36 0)
			(effects
				(font
					(size 1.27 1.27)
					(thickness 0.15)
				)
				(justify left bottom)
				(hide yes)
			)
		)
		(property "Value" "GND"
			(at 146.05 88.265 0)
			(effects
				(font
					(size 1.27 1.27)
					(thickness 0.15)
				)
			)
		)
		(property "Footprint" ""
			(at 137.16 91.44 0)
			(effects
				(font
					(size 1.27 1.27)
					(thickness 0.15)
				)
				(justify left bottom)
				(hide yes)
			)
		)
		(property "Datasheet" ""
			(at 137.16 96.52 0)
			(effects
				(font
					(size 1.27 1.27)
					(thickness 0.15)
				)
				(justify left bottom)
				(hide yes)
			)
		)
		(property "Description" ""
			(at 146.05 83.82 0)
			(effects
				(font
					(size 1.27 1.27)
				)
				(hide yes)
			)
		)
		(property "Author" "Antmicro"
			(at 137.16 91.44 0)
			(effects
				(font
					(size 1.27 1.27)
					(thickness 0.15)
				)
				(justify left bottom)
				(hide yes)
			)
		)
		(property "License" "Apache-2.0"
			(at 137.16 93.98 0)
			(effects
				(font
					(size 1.27 1.27)
					(thickness 0.15)
				)
				(justify left bottom)
				(hide yes)
			)
		)
		(pin "1"
		)
		(instances
			(project "usb-c-power-adapter"
				(path ""
					(reference "#PWR018")
					(unit 1)
				)
			)
		)
	)
	(symbol
		(lib_id "antmicroResistors0402:R_470R_0402")
		(at 241.3 135.89 90)
		(unit 1)
		(exclude_from_sim no)
		(in_bom yes)
		(on_board yes)
		(dnp no)
		(fields_autoplaced yes)
		(property "Reference" "R25"
			(at 243.84 132.08 90)
			(effects
				(font
					(size 1.27 1.27)
					(thickness 0.15)
				)
				(justify right)
			)
		)
		(property "Value" "R_470R_0402"
			(at 254 115.57 0)
			(effects
				(font
					(size 1.27 1.27)
					(thickness 0.15)
				)
				(justify left bottom)
				(hide yes)
			)
		)
		(property "Footprint" "antmicro-footprints:R_0402_1005Metric"
			(at 256.54 115.57 0)
			(effects
				(font
					(size 1.27 1.27)
					(thickness 0.15)
				)
				(justify left bottom)
				(hide yes)
			)
		)
		(property "Datasheet" "https://www.bourns.com/docs/product-datasheets/cr.pdf"
			(at 259.08 115.57 0)
			(effects
				(font
					(size 1.27 1.27)
					(thickness 0.15)
				)
				(justify left bottom)
				(hide yes)
			)
		)
		(property "Description" "SMD Chip Resistor, 470 ohm, ± 1%, 62.5 mW, 0402 [1005 Metric], Thick Film, General Purpose"
			(at 241.3 135.89 0)
			(effects
				(font
					(size 1.27 1.27)
				)
				(hide yes)
			)
		)
		(property "MPN" "CR0402-FX-4700GLF"
			(at 261.62 115.57 0)
			(effects
				(font
					(size 1.27 1.27)
					(thickness 0.15)
				)
				(justify left bottom)
				(hide yes)
			)
		)
		(property "Manufacturer" "Bourns"
			(at 264.16 115.57 0)
			(effects
				(font
					(size 1.27 1.27)
					(thickness 0.15)
				)
				(justify left bottom)
				(hide yes)
			)
		)
		(property "License" "Apache-2.0"
			(at 266.7 115.57 0)
			(effects
				(font
					(size 1.27 1.27)
					(thickness 0.15)
				)
				(justify left bottom)
				(hide yes)
			)
		)
		(property "Author" "Antmicro"
			(at 269.24 115.57 0)
			(effects
				(font
					(size 1.27 1.27)
					(thickness 0.15)
				)
				(justify left bottom)
				(hide yes)
			)
		)
		(property "Val" "470R"
			(at 243.84 134.62 90)
			(effects
				(font
					(size 1.27 1.27)
					(thickness 0.15)
				)
				(justify right)
			)
		)
		(property "Tolerance" "1%"
			(at 251.46 115.57 0)
			(effects
				(font
					(size 1.27 1.27)
				)
				(justify left bottom)
				(hide yes)
			)
		)
		(pin "2"
		)
		(pin "1"
		)
		(instances
			(project "usb-c-power-adapter"
				(path ""
					(reference "R25")
					(unit 1)
				)
			)
		)
	)
	(symbol
		(lib_id "antmicroTestPoints:TP_0.75mm_SMD")
		(at 179.07 146.05 0)
		(unit 1)
		(exclude_from_sim no)
		(in_bom no)
		(on_board yes)
		(dnp no)
		(fields_autoplaced yes)
		(property "Reference" "TP2"
			(at 184.15 146.05 0)
			(effects
				(font
					(size 1.27 1.27)
					(thickness 0.15)
				)
				(justify left)
			)
		)
		(property "Value" "TP_0.75mm_SMD"
			(at 189.865 149.86 0)
			(effects
				(font
					(size 1.27 1.27)
					(thickness 0.15)
				)
				(justify left bottom)
				(hide yes)
			)
		)
		(property "Footprint" "antmicro-footprints:TP_SMD_0.75mm"
			(at 189.865 152.4 0)
			(effects
				(font
					(size 1.27 1.27)
					(thickness 0.15)
				)
				(justify left bottom)
				(hide yes)
			)
		)
		(property "Datasheet" ""
			(at 196.85 158.75 0)
			(effects
				(font
					(size 1.27 1.27)
					(thickness 0.15)
				)
				(justify left bottom)
				(hide yes)
			)
		)
		(property "Description" "SMT test point"
			(at 179.07 146.05 0)
			(effects
				(font
					(size 1.27 1.27)
				)
				(hide yes)
			)
		)
		(property "MPN" ""
			(at 189.865 157.48 0)
			(effects
				(font
					(size 1.27 1.27)
					(thickness 0.15)
				)
				(justify left bottom)
				(hide yes)
			)
		)
		(property "Manufacturer" ""
			(at 189.865 152.4 0)
			(effects
				(font
					(size 1.27 1.27)
					(thickness 0.15)
				)
				(justify left bottom)
				(hide yes)
			)
		)
		(property "Author" "Antmicro"
			(at 189.865 154.94 0)
			(effects
				(font
					(size 1.27 1.27)
					(thickness 0.15)
				)
				(justify left bottom)
				(hide yes)
			)
		)
		(property "License" "Apache-2.0"
			(at 189.865 157.48 0)
			(effects
				(font
					(size 1.27 1.27)
					(thickness 0.15)
				)
				(justify left bottom)
				(hide yes)
			)
		)
		(pin "1"
		)
		(instances
			(project "usb-c-power-adapter"
				(path ""
					(reference "TP2")
					(unit 1)
				)
			)
		)
	)
	(symbol
		(lib_id "antmicropower:GND")
		(at 106.68 114.3 0)
		(mirror y)
		(unit 1)
		(exclude_from_sim no)
		(in_bom yes)
		(on_board yes)
		(dnp no)
		(property "Reference" "#PWR074"
			(at 97.79 116.84 0)
			(effects
				(font
					(size 1.27 1.27)
					(thickness 0.15)
				)
				(justify left bottom)
				(hide yes)
			)
		)
		(property "Value" "GND"
			(at 110.49 115.57 0)
			(effects
				(font
					(size 1.27 1.27)
					(thickness 0.15)
				)
			)
		)
		(property "Footprint" ""
			(at 97.79 121.92 0)
			(effects
				(font
					(size 1.27 1.27)
					(thickness 0.15)
				)
				(justify left bottom)
				(hide yes)
			)
		)
		(property "Datasheet" ""
			(at 97.79 127 0)
			(effects
				(font
					(size 1.27 1.27)
					(thickness 0.15)
				)
				(justify left bottom)
				(hide yes)
			)
		)
		(property "Description" ""
			(at 106.68 114.3 0)
			(effects
				(font
					(size 1.27 1.27)
				)
				(hide yes)
			)
		)
		(property "Author" "Antmicro"
			(at 97.79 121.92 0)
			(effects
				(font
					(size 1.27 1.27)
					(thickness 0.15)
				)
				(justify left bottom)
				(hide yes)
			)
		)
		(property "License" "Apache-2.0"
			(at 97.79 124.46 0)
			(effects
				(font
					(size 1.27 1.27)
					(thickness 0.15)
				)
				(justify left bottom)
				(hide yes)
			)
		)
		(pin "1"
		)
		(instances
			(project "usb-c-power-adapter"
				(path ""
					(reference "#PWR074")
					(unit 1)
				)
			)
		)
	)
	(symbol
		(lib_id "antmicroResistors0402:R_4k7_0402")
		(at 179.07 132.08 90)
		(unit 1)
		(exclude_from_sim no)
		(in_bom no)
		(on_board yes)
		(dnp yes)
		(fields_autoplaced yes)
		(property "Reference" "R32"
			(at 181.61 128.27 90)
			(effects
				(font
					(size 1.27 1.27)
					(thickness 0.15)
				)
				(justify right)
			)
		)
		(property "Value" "R_4k7_0402"
			(at 191.77 111.76 0)
			(effects
				(font
					(size 1.27 1.27)
					(thickness 0.15)
				)
				(justify left bottom)
				(hide yes)
			)
		)
		(property "Footprint" "antmicro-footprints:R_0402_1005Metric"
			(at 194.31 111.76 0)
			(effects
				(font
					(size 1.27 1.27)
					(thickness 0.15)
				)
				(justify left bottom)
				(hide yes)
			)
		)
		(property "Datasheet" "https://www.bourns.com/docs/product-datasheets/cr.pdf"
			(at 196.85 111.76 0)
			(effects
				(font
					(size 1.27 1.27)
					(thickness 0.15)
				)
				(justify left bottom)
				(hide yes)
			)
		)
		(property "Description" "SMD Chip Resistor, 4.7 kohm, ± 1%, 62.5 mW, 0402 [1005 Metric], Thick Film, General Purpose"
			(at 179.07 132.08 0)
			(effects
				(font
					(size 1.27 1.27)
				)
				(hide yes)
			)
		)
		(property "MPN" "CR0402-FX-4701GLF"
			(at 199.39 111.76 0)
			(effects
				(font
					(size 1.27 1.27)
					(thickness 0.15)
				)
				(justify left bottom)
				(hide yes)
			)
		)
		(property "Manufacturer" "Bourns"
			(at 201.93 111.76 0)
			(effects
				(font
					(size 1.27 1.27)
					(thickness 0.15)
				)
				(justify left bottom)
				(hide yes)
			)
		)
		(property "License" "Apache-2.0"
			(at 204.47 111.76 0)
			(effects
				(font
					(size 1.27 1.27)
					(thickness 0.15)
				)
				(justify left bottom)
				(hide yes)
			)
		)
		(property "Author" "Antmicro"
			(at 207.01 111.76 0)
			(effects
				(font
					(size 1.27 1.27)
					(thickness 0.15)
				)
				(justify left bottom)
				(hide yes)
			)
		)
		(property "Val" "4k7"
			(at 181.61 130.81 90)
			(effects
				(font
					(size 1.27 1.27)
					(thickness 0.15)
				)
				(justify right)
			)
		)
		(property "Tolerance" "1%"
			(at 189.23 111.76 0)
			(effects
				(font
					(size 1.27 1.27)
				)
				(justify left bottom)
				(hide yes)
			)
		)
		(pin "2"
		)
		(pin "1"
		)
		(instances
			(project "usb-c-power-adapter"
				(path ""
					(reference "R32")
					(unit 1)
				)
			)
		)
	)
	(symbol
		(lib_id "antmicropower:+5V")
		(at 241.3 127 0)
		(unit 1)
		(exclude_from_sim no)
		(in_bom yes)
		(on_board yes)
		(dnp no)
		(fields_autoplaced yes)
		(property "Reference" "#PWR025"
			(at 256.54 129.54 0)
			(effects
				(font
					(size 1.27 1.27)
					(thickness 0.15)
				)
				(justify left bottom)
				(hide yes)
			)
		)
		(property "Value" "+5V"
			(at 241.3 121.92 0)
			(effects
				(font
					(size 1.27 1.27)
					(thickness 0.15)
				)
			)
		)
		(property "Footprint" ""
			(at 256.54 134.62 0)
			(effects
				(font
					(size 1.27 1.27)
					(thickness 0.15)
				)
				(justify left bottom)
				(hide yes)
			)
		)
		(property "Datasheet" ""
			(at 256.54 137.16 0)
			(effects
				(font
					(size 1.27 1.27)
					(thickness 0.15)
				)
				(justify left bottom)
				(hide yes)
			)
		)
		(property "Description" ""
			(at 241.3 127 0)
			(effects
				(font
					(size 1.27 1.27)
				)
				(hide yes)
			)
		)
		(property "Author" "Antmicro"
			(at 256.54 134.62 0)
			(effects
				(font
					(size 1.27 1.27)
					(thickness 0.15)
				)
				(justify left bottom)
				(hide yes)
			)
		)
		(property "License" "Apache-2.0"
			(at 256.54 137.16 0)
			(effects
				(font
					(size 1.27 1.27)
					(thickness 0.15)
				)
				(justify left bottom)
				(hide yes)
			)
		)
		(pin "1"
		)
		(instances
			(project "usb-c-power-adapter"
				(path ""
					(reference "#PWR025")
					(unit 1)
				)
			)
		)
	)
	(symbol
		(lib_id "antmicroCapacitorsmisc:C_10u_0805_35V")
		(at 146.05 80.01 90)
		(unit 1)
		(exclude_from_sim no)
		(in_bom yes)
		(on_board yes)
		(dnp no)
		(fields_autoplaced yes)
		(property "Reference" "C7"
			(at 148.59 76.1936 90)
			(effects
				(font
					(size 1.27 1.27)
					(thickness 0.15)
				)
				(justify right)
			)
		)
		(property "Value" "C_10u_0805_35V"
			(at 156.21 59.69 0)
			(effects
				(font
					(size 1.27 1.27)
					(thickness 0.15)
				)
				(justify left bottom)
				(hide yes)
			)
		)
		(property "Footprint" "antmicro-footprints:C_0805_2012Metric"
			(at 158.75 59.69 0)
			(effects
				(font
					(size 1.27 1.27)
					(thickness 0.15)
				)
				(justify left bottom)
				(hide yes)
			)
		)
		(property "Datasheet" "https://www.murata.com/products/productdetail?partno=GRM21BR6YA106KE43%23"
			(at 161.29 59.69 0)
			(effects
				(font
					(size 1.27 1.27)
					(thickness 0.15)
				)
				(justify left bottom)
				(hide yes)
			)
		)
		(property "Description" "SMD Multilayer Ceramic Capacitor, 10 µF, 35 V, 0805 [2012 Metric], ± 10%, X5R, GRM Series"
			(at 146.05 80.01 0)
			(effects
				(font
					(size 1.27 1.27)
				)
				(hide yes)
			)
		)
		(property "MPN" "GRM21BR6YA106KE43L"
			(at 163.83 59.69 0)
			(effects
				(font
					(size 1.27 1.27)
					(thickness 0.15)
				)
				(justify left bottom)
				(hide yes)
			)
		)
		(property "Manufacturer" "Murata"
			(at 166.37 59.69 0)
			(effects
				(font
					(size 1.27 1.27)
					(thickness 0.15)
				)
				(justify left bottom)
				(hide yes)
			)
		)
		(property "License" "Apache-2.0"
			(at 168.91 59.69 0)
			(effects
				(font
					(size 1.27 1.27)
					(thickness 0.15)
				)
				(justify left bottom)
				(hide yes)
			)
		)
		(property "Author" "Antmicro"
			(at 171.45 59.69 0)
			(effects
				(font
					(size 1.27 1.27)
					(thickness 0.15)
				)
				(justify left bottom)
				(hide yes)
			)
		)
		(property "Val" "10u"
			(at 148.59 78.7336 90)
			(effects
				(font
					(size 1.27 1.27)
					(thickness 0.15)
				)
				(justify right)
			)
		)
		(property "Voltage" "35V"
			(at 173.99 59.69 0)
			(effects
				(font
					(size 1.27 1.27)
				)
				(justify left bottom)
				(hide yes)
			)
		)
		(property "Dielectric" ""
			(at 176.53 59.69 0)
			(effects
				(font
					(size 1.27 1.27)
				)
				(justify left bottom)
				(hide yes)
			)
		)
		(property "Public" "False"
			(at 179.07 59.69 0)
			(effects
				(font
					(size 1.27 1.27)
				)
				(justify left bottom)
				(hide yes)
			)
		)
		(pin "2"
		)
		(pin "1"
		)
		(instances
			(project "usb-c-power-adapter"
				(path ""
					(reference "C7")
					(unit 1)
				)
			)
		)
	)
	(symbol
		(lib_id "antmicroWire2BoardConnectors:JST_SH_1x4_SM04B-SRSS-TB-LF-SN")
		(at 144.78 132.08 0)
		(mirror y)
		(unit 1)
		(exclude_from_sim no)
		(in_bom yes)
		(on_board yes)
		(dnp no)
		(fields_autoplaced yes)
		(property "Reference" "J2"
			(at 140.97 124.46 0)
			(effects
				(font
					(size 1.27 1.27)
					(thickness 0.15)
				)
			)
		)
		(property "Value" "JST_SH_1x4_SM04B-SRSS-TB-LF-SN"
			(at 118.11 139.7 0)
			(effects
				(font
					(size 1.27 1.27)
					(thickness 0.15)
				)
				(justify left bottom)
				(hide yes)
			)
		)
		(property "Footprint" "antmicro-footprints:Conn_JST_SH_1x4_SM04B-SRSS-TB-LF-SN"
			(at 118.11 142.24 0)
			(effects
				(font
					(size 1.27 1.27)
					(thickness 0.15)
				)
				(justify left bottom)
				(hide yes)
			)
		)
		(property "Datasheet" "https://www.jst-mfg.com/product/pdf/eng/eSH.pdf"
			(at 118.11 144.78 0)
			(effects
				(font
					(size 1.27 1.27)
					(thickness 0.15)
				)
				(justify left bottom)
				(hide yes)
			)
		)
		(property "Description" "Pin Header, Right Angle, Wire-to-Board, 1 mm, 1 Rows, 4 Contacts, Surface Mount Right Angle, SH"
			(at 144.78 132.08 0)
			(effects
				(font
					(size 1.27 1.27)
				)
				(hide yes)
			)
		)
		(property "MPN" "SM04B-SRSS-TB(LF)(SN)"
			(at 140.97 127 0)
			(effects
				(font
					(size 1.27 1.27)
					(thickness 0.15)
				)
			)
		)
		(property "Manufacturer" "JST Automotive Connectors"
			(at 118.11 147.32 0)
			(effects
				(font
					(size 1.27 1.27)
					(thickness 0.15)
				)
				(justify left bottom)
				(hide yes)
			)
		)
		(property "Author" "Antmicro"
			(at 118.11 149.86 0)
			(effects
				(font
					(size 1.27 1.27)
					(thickness 0.15)
				)
				(justify left bottom)
				(hide yes)
			)
		)
		(property "License" "Apache-2.0"
			(at 118.11 152.4 0)
			(effects
				(font
					(size 1.27 1.27)
					(thickness 0.15)
				)
				(justify left bottom)
				(hide yes)
			)
		)
		(pin "1"
		)
		(pin "4"
		)
		(pin "MP"
		)
		(pin "2"
		)
		(pin "3"
		)
		(instances
			(project "usb-c-power-adapter"
				(path ""
					(reference "J2")
					(unit 1)
				)
			)
		)
	)
	(symbol
		(lib_id "antmicroTestPoints:TP_0.75mm_SMD")
		(at 179.07 143.51 0)
		(unit 1)
		(exclude_from_sim no)
		(in_bom no)
		(on_board yes)
		(dnp no)
		(fields_autoplaced yes)
		(property "Reference" "TP1"
			(at 184.15 143.51 0)
			(effects
				(font
					(size 1.27 1.27)
					(thickness 0.15)
				)
				(justify left)
			)
		)
		(property "Value" "TP_0.75mm_SMD"
			(at 189.865 147.32 0)
			(effects
				(font
					(size 1.27 1.27)
					(thickness 0.15)
				)
				(justify left bottom)
				(hide yes)
			)
		)
		(property "Footprint" "antmicro-footprints:TP_SMD_0.75mm"
			(at 189.865 149.86 0)
			(effects
				(font
					(size 1.27 1.27)
					(thickness 0.15)
				)
				(justify left bottom)
				(hide yes)
			)
		)
		(property "Datasheet" ""
			(at 196.85 156.21 0)
			(effects
				(font
					(size 1.27 1.27)
					(thickness 0.15)
				)
				(justify left bottom)
				(hide yes)
			)
		)
		(property "Description" "SMT test point"
			(at 179.07 143.51 0)
			(effects
				(font
					(size 1.27 1.27)
				)
				(hide yes)
			)
		)
		(property "MPN" ""
			(at 189.865 154.94 0)
			(effects
				(font
					(size 1.27 1.27)
					(thickness 0.15)
				)
				(justify left bottom)
				(hide yes)
			)
		)
		(property "Manufacturer" ""
			(at 189.865 149.86 0)
			(effects
				(font
					(size 1.27 1.27)
					(thickness 0.15)
				)
				(justify left bottom)
				(hide yes)
			)
		)
		(property "Author" "Antmicro"
			(at 189.865 152.4 0)
			(effects
				(font
					(size 1.27 1.27)
					(thickness 0.15)
				)
				(justify left bottom)
				(hide yes)
			)
		)
		(property "License" "Apache-2.0"
			(at 189.865 154.94 0)
			(effects
				(font
					(size 1.27 1.27)
					(thickness 0.15)
				)
				(justify left bottom)
				(hide yes)
			)
		)
		(pin "1"
		)
		(instances
			(project "usb-c-power-adapter"
				(path ""
					(reference "TP1")
					(unit 1)
				)
			)
		)
	)
	(symbol
		(lib_id "antmicroTestPoints:TP_0.75mm_SMD")
		(at 213.36 83.82 180)
		(unit 1)
		(exclude_from_sim no)
		(in_bom no)
		(on_board yes)
		(dnp no)
		(property "Reference" "TP9"
			(at 207.01 83.82 0)
			(effects
				(font
					(size 1.27 1.27)
					(thickness 0.15)
				)
			)
		)
		(property "Value" "TP_0.75mm_SMD"
			(at 202.565 80.01 0)
			(effects
				(font
					(size 1.27 1.27)
					(thickness 0.15)
				)
				(justify left bottom)
				(hide yes)
			)
		)
		(property "Footprint" "antmicro-footprints:TP_SMD_0.75mm"
			(at 202.565 77.47 0)
			(effects
				(font
					(size 1.27 1.27)
					(thickness 0.15)
				)
				(justify left bottom)
				(hide yes)
			)
		)
		(property "Datasheet" ""
			(at 195.58 71.12 0)
			(effects
				(font
					(size 1.27 1.27)
					(thickness 0.15)
				)
				(justify left bottom)
				(hide yes)
			)
		)
		(property "Description" "SMT test point"
			(at 213.36 83.82 0)
			(effects
				(font
					(size 1.27 1.27)
				)
				(hide yes)
			)
		)
		(property "MPN" ""
			(at 202.565 72.39 0)
			(effects
				(font
					(size 1.27 1.27)
					(thickness 0.15)
				)
				(justify left bottom)
				(hide yes)
			)
		)
		(property "Manufacturer" ""
			(at 202.565 77.47 0)
			(effects
				(font
					(size 1.27 1.27)
					(thickness 0.15)
				)
				(justify left bottom)
				(hide yes)
			)
		)
		(property "Author" "Antmicro"
			(at 202.565 74.93 0)
			(effects
				(font
					(size 1.27 1.27)
					(thickness 0.15)
				)
				(justify left bottom)
				(hide yes)
			)
		)
		(property "License" "Apache-2.0"
			(at 202.565 72.39 0)
			(effects
				(font
					(size 1.27 1.27)
					(thickness 0.15)
				)
				(justify left bottom)
				(hide yes)
			)
		)
		(pin "1"
		)
		(instances
			(project "usb-c-power-adapter"
				(path ""
					(reference "TP9")
					(unit 1)
				)
			)
		)
	)
	(symbol
		(lib_id "antmicropower:GND")
		(at 269.24 92.71 0)
		(mirror y)
		(unit 1)
		(exclude_from_sim no)
		(in_bom yes)
		(on_board yes)
		(dnp no)
		(fields_autoplaced yes)
		(property "Reference" "#PWR081"
			(at 260.35 95.25 0)
			(effects
				(font
					(size 1.27 1.27)
					(thickness 0.15)
				)
				(justify left bottom)
				(hide yes)
			)
		)
		(property "Value" "GND"
			(at 269.24 97.155 0)
			(effects
				(font
					(size 1.27 1.27)
					(thickness 0.15)
				)
			)
		)
		(property "Footprint" ""
			(at 260.35 100.33 0)
			(effects
				(font
					(size 1.27 1.27)
					(thickness 0.15)
				)
				(justify left bottom)
				(hide yes)
			)
		)
		(property "Datasheet" ""
			(at 260.35 105.41 0)
			(effects
				(font
					(size 1.27 1.27)
					(thickness 0.15)
				)
				(justify left bottom)
				(hide yes)
			)
		)
		(property "Description" ""
			(at 269.24 92.71 0)
			(effects
				(font
					(size 1.27 1.27)
				)
				(hide yes)
			)
		)
		(property "Author" "Antmicro"
			(at 260.35 100.33 0)
			(effects
				(font
					(size 1.27 1.27)
					(thickness 0.15)
				)
				(justify left bottom)
				(hide yes)
			)
		)
		(property "License" "Apache-2.0"
			(at 260.35 102.87 0)
			(effects
				(font
					(size 1.27 1.27)
					(thickness 0.15)
				)
				(justify left bottom)
				(hide yes)
			)
		)
		(pin "1"
		)
		(instances
			(project "usb-c-power-adapter"
				(path ""
					(reference "#PWR081")
					(unit 1)
				)
			)
		)
	)
	(symbol
		(lib_id "antmicroResistors0603:R_4k7_0603")
		(at 200.66 55.88 0)
		(mirror x)
		(unit 1)
		(exclude_from_sim no)
		(in_bom yes)
		(on_board yes)
		(dnp no)
		(property "Reference" "R3"
			(at 203.2 51.816 0)
			(effects
				(font
					(size 1.27 1.27)
					(thickness 0.15)
				)
			)
		)
		(property "Value" "R_4k7_0603"
			(at 220.98 43.18 0)
			(effects
				(font
					(size 1.27 1.27)
					(thickness 0.15)
				)
				(justify left bottom)
				(hide yes)
			)
		)
		(property "Footprint" "antmicro-footprints:R_0603_1608Metric"
			(at 220.98 40.64 0)
			(effects
				(font
					(size 1.27 1.27)
					(thickness 0.15)
				)
				(justify left bottom)
				(hide yes)
			)
		)
		(property "Datasheet" "https://www.bourns.com/docs/product-datasheets/cr.pdf"
			(at 220.98 38.1 0)
			(effects
				(font
					(size 1.27 1.27)
					(thickness 0.15)
				)
				(justify left bottom)
				(hide yes)
			)
		)
		(property "Description" "SMD Chip Resistor, 4.7 kohm, ± 1%, 100 mW, 0603 [1608 Metric], Thick Film, General Purpose"
			(at 200.66 55.88 0)
			(effects
				(font
					(size 1.27 1.27)
				)
				(hide yes)
			)
		)
		(property "MPN" "CR0603-FX-4701ELF"
			(at 220.98 35.56 0)
			(effects
				(font
					(size 1.27 1.27)
					(thickness 0.15)
				)
				(justify left bottom)
				(hide yes)
			)
		)
		(property "Manufacturer" "Bourns"
			(at 220.98 33.02 0)
			(effects
				(font
					(size 1.27 1.27)
					(thickness 0.15)
				)
				(justify left bottom)
				(hide yes)
			)
		)
		(property "License" "Apache-2.0"
			(at 220.98 30.48 0)
			(effects
				(font
					(size 1.27 1.27)
					(thickness 0.15)
				)
				(justify left bottom)
				(hide yes)
			)
		)
		(property "Author" "Antmicro"
			(at 220.98 27.94 0)
			(effects
				(font
					(size 1.27 1.27)
					(thickness 0.15)
				)
				(justify left bottom)
				(hide yes)
			)
		)
		(property "Val" "4k7"
			(at 203.2 53.848 0)
			(effects
				(font
					(size 1.27 1.27)
					(thickness 0.15)
				)
			)
		)
		(property "Tolerance" "1%"
			(at 220.98 45.72 0)
			(effects
				(font
					(size 1.27 1.27)
				)
				(justify left bottom)
				(hide yes)
			)
		)
		(pin "2"
		)
		(pin "1"
		)
		(instances
			(project "usb-c-power-adapter"
				(path ""
					(reference "R3")
					(unit 1)
				)
			)
		)
	)
	(symbol
		(lib_id "antmicropower:GND")
		(at 106.68 82.55 0)
		(mirror y)
		(unit 1)
		(exclude_from_sim no)
		(in_bom yes)
		(on_board yes)
		(dnp no)
		(property "Reference" "#PWR047"
			(at 97.79 85.09 0)
			(effects
				(font
					(size 1.27 1.27)
					(thickness 0.15)
				)
				(justify left bottom)
				(hide yes)
			)
		)
		(property "Value" "GND"
			(at 110.49 83.82 0)
			(effects
				(font
					(size 1.27 1.27)
					(thickness 0.15)
				)
			)
		)
		(property "Footprint" ""
			(at 97.79 90.17 0)
			(effects
				(font
					(size 1.27 1.27)
					(thickness 0.15)
				)
				(justify left bottom)
				(hide yes)
			)
		)
		(property "Datasheet" ""
			(at 97.79 95.25 0)
			(effects
				(font
					(size 1.27 1.27)
					(thickness 0.15)
				)
				(justify left bottom)
				(hide yes)
			)
		)
		(property "Description" ""
			(at 106.68 82.55 0)
			(effects
				(font
					(size 1.27 1.27)
				)
				(hide yes)
			)
		)
		(property "Author" "Antmicro"
			(at 97.79 90.17 0)
			(effects
				(font
					(size 1.27 1.27)
					(thickness 0.15)
				)
				(justify left bottom)
				(hide yes)
			)
		)
		(property "License" "Apache-2.0"
			(at 97.79 92.71 0)
			(effects
				(font
					(size 1.27 1.27)
					(thickness 0.15)
				)
				(justify left bottom)
				(hide yes)
			)
		)
		(pin "1"
		)
		(instances
			(project "usb-c-power-adapter"
				(path ""
					(reference "#PWR047")
					(unit 1)
				)
			)
		)
	)
	(symbol
		(lib_id "antmicropower:VBUS")
		(at 292.1 58.42 0)
		(unit 1)
		(exclude_from_sim no)
		(in_bom yes)
		(on_board yes)
		(dnp no)
		(property "Reference" "#PWR019"
			(at 292.1 62.23 0)
			(effects
				(font
					(size 1.27 1.27)
				)
				(hide yes)
			)
		)
		(property "Value" "VBUS"
			(at 292.1 53.34 0)
			(effects
				(font
					(size 1.27 1.27)
				)
			)
		)
		(property "Footprint" ""
			(at 292.1 58.42 0)
			(effects
				(font
					(size 1.27 1.27)
				)
				(hide yes)
			)
		)
		(property "Datasheet" ""
			(at 292.1 58.42 0)
			(effects
				(font
					(size 1.27 1.27)
				)
				(hide yes)
			)
		)
		(property "Description" ""
			(at 292.1 58.42 0)
			(effects
				(font
					(size 1.27 1.27)
				)
				(hide yes)
			)
		)
		(pin "1"
		)
		(instances
			(project "usb-c-power-adapter"
				(path ""
					(reference "#PWR019")
					(unit 1)
				)
			)
		)
	)
	(symbol
		(lib_id "antmicroTestPoints:TP_0.75mm_SMD")
		(at 339.09 87.63 90)
		(unit 1)
		(exclude_from_sim no)
		(in_bom no)
		(on_board yes)
		(dnp no)
		(property "Reference" "TP13"
			(at 339.09 81.28 90)
			(effects
				(font
					(size 1.27 1.27)
					(thickness 0.15)
				)
			)
		)
		(property "Value" "TP_0.75mm_SMD"
			(at 342.9 76.835 0)
			(effects
				(font
					(size 1.27 1.27)
					(thickness 0.15)
				)
				(justify left bottom)
				(hide yes)
			)
		)
		(property "Footprint" "antmicro-footprints:TP_SMD_0.75mm"
			(at 345.44 76.835 0)
			(effects
				(font
					(size 1.27 1.27)
					(thickness 0.15)
				)
				(justify left bottom)
				(hide yes)
			)
		)
		(property "Datasheet" ""
			(at 351.79 69.85 0)
			(effects
				(font
					(size 1.27 1.27)
					(thickness 0.15)
				)
				(justify left bottom)
				(hide yes)
			)
		)
		(property "Description" "SMT test point"
			(at 339.09 87.63 0)
			(effects
				(font
					(size 1.27 1.27)
				)
				(hide yes)
			)
		)
		(property "MPN" ""
			(at 350.52 76.835 0)
			(effects
				(font
					(size 1.27 1.27)
					(thickness 0.15)
				)
				(justify left bottom)
				(hide yes)
			)
		)
		(property "Manufacturer" ""
			(at 345.44 76.835 0)
			(effects
				(font
					(size 1.27 1.27)
					(thickness 0.15)
				)
				(justify left bottom)
				(hide yes)
			)
		)
		(property "Author" "Antmicro"
			(at 347.98 76.835 0)
			(effects
				(font
					(size 1.27 1.27)
					(thickness 0.15)
				)
				(justify left bottom)
				(hide yes)
			)
		)
		(property "License" "Apache-2.0"
			(at 350.52 76.835 0)
			(effects
				(font
					(size 1.27 1.27)
					(thickness 0.15)
				)
				(justify left bottom)
				(hide yes)
			)
		)
		(pin "1"
		)
		(instances
			(project "usb-c-power-adapter"
				(path ""
					(reference "TP13")
					(unit 1)
				)
			)
		)
	)
	(symbol
		(lib_id "antmicropower:VBUS")
		(at 106.68 78.74 0)
		(mirror y)
		(unit 1)
		(exclude_from_sim no)
		(in_bom yes)
		(on_board yes)
		(dnp no)
		(fields_autoplaced yes)
		(property "Reference" "#PWR046"
			(at 106.68 82.55 0)
			(effects
				(font
					(size 1.27 1.27)
				)
				(hide yes)
			)
		)
		(property "Value" "VBUS"
			(at 106.68 73.66 0)
			(effects
				(font
					(size 1.27 1.27)
				)
			)
		)
		(property "Footprint" ""
			(at 106.68 78.74 0)
			(effects
				(font
					(size 1.27 1.27)
				)
				(hide yes)
			)
		)
		(property "Datasheet" ""
			(at 106.68 78.74 0)
			(effects
				(font
					(size 1.27 1.27)
				)
				(hide yes)
			)
		)
		(property "Description" ""
			(at 106.68 78.74 0)
			(effects
				(font
					(size 1.27 1.27)
				)
				(hide yes)
			)
		)
		(pin "1"
		)
		(instances
			(project "usb-c-power-adapter"
				(path ""
					(reference "#PWR046")
					(unit 1)
				)
			)
		)
	)
	(symbol
		(lib_id "antmicroCapacitors0402:C_100n_50V_X8L_0402")
		(at 326.39 68.58 90)
		(unit 1)
		(exclude_from_sim no)
		(in_bom yes)
		(on_board yes)
		(dnp no)
		(fields_autoplaced yes)
		(property "Reference" "C19"
			(at 328.93 64.7636 90)
			(effects
				(font
					(size 1.27 1.27)
					(thickness 0.15)
				)
				(justify right)
			)
		)
		(property "Value" "C_100n_50V_X8L_0402"
			(at 349.25 53.34 0)
			(effects
				(font
					(size 1.27 1.27)
					(thickness 0.15)
				)
				(justify left bottom)
				(hide yes)
			)
		)
		(property "Footprint" "antmicro-footprints:C_0402_1005Metric"
			(at 351.79 53.34 0)
			(effects
				(font
					(size 1.27 1.27)
					(thickness 0.15)
				)
				(justify left bottom)
				(hide yes)
			)
		)
		(property "Datasheet" "https://www.murata.com/products/productdetail?partno=GCM155L8EH104KE07%23"
			(at 354.33 53.34 0)
			(effects
				(font
					(size 1.27 1.27)
					(thickness 0.15)
				)
				(justify left bottom)
				(hide yes)
			)
		)
		(property "Description" "SMD Multilayer Ceramic Capacitor, 100nF, 50V, 0402, ±10%, X8L"
			(at 326.39 68.58 0)
			(effects
				(font
					(size 1.27 1.27)
				)
				(hide yes)
			)
		)
		(property "MPN" "GCM155L8EH104KE07D"
			(at 356.87 53.34 0)
			(effects
				(font
					(size 1.27 1.27)
					(thickness 0.15)
				)
				(justify left bottom)
				(hide yes)
			)
		)
		(property "Val" "100n"
			(at 328.93 67.3036 90)
			(effects
				(font
					(size 1.27 1.27)
					(thickness 0.15)
				)
				(justify right)
			)
		)
		(property "Voltage" "50V"
			(at 336.55 53.34 0)
			(effects
				(font
					(size 1.27 1.27)
					(thickness 0.15)
				)
				(justify left bottom)
				(hide yes)
			)
		)
		(property "Dielectric" "X8L"
			(at 339.09 53.34 0)
			(effects
				(font
					(size 1.27 1.27)
					(thickness 0.15)
				)
				(justify left bottom)
				(hide yes)
			)
		)
		(property "Manufacturer" "Murata"
			(at 341.63 53.34 0)
			(effects
				(font
					(size 1.27 1.27)
					(thickness 0.15)
				)
				(justify left bottom)
				(hide yes)
			)
		)
		(property "License" "Apache-2.0"
			(at 344.17 53.34 0)
			(effects
				(font
					(size 1.27 1.27)
					(thickness 0.15)
				)
				(justify left bottom)
				(hide yes)
			)
		)
		(property "Author" "Antmicro"
			(at 346.71 53.34 0)
			(effects
				(font
					(size 1.27 1.27)
					(thickness 0.15)
				)
				(justify left bottom)
				(hide yes)
			)
		)
		(pin "1"
		)
		(pin "2"
		)
		(instances
			(project "usb-c-power-adapter"
				(path ""
					(reference "C19")
					(unit 1)
				)
			)
		)
	)
	(symbol
		(lib_id "antmicropower:+5V")
		(at 260.35 127 0)
		(unit 1)
		(exclude_from_sim no)
		(in_bom yes)
		(on_board yes)
		(dnp no)
		(fields_autoplaced yes)
		(property "Reference" "#PWR026"
			(at 275.59 129.54 0)
			(effects
				(font
					(size 1.27 1.27)
					(thickness 0.15)
				)
				(justify left bottom)
				(hide yes)
			)
		)
		(property "Value" "+5V"
			(at 260.35 121.92 0)
			(effects
				(font
					(size 1.27 1.27)
					(thickness 0.15)
				)
			)
		)
		(property "Footprint" ""
			(at 275.59 134.62 0)
			(effects
				(font
					(size 1.27 1.27)
					(thickness 0.15)
				)
				(justify left bottom)
				(hide yes)
			)
		)
		(property "Datasheet" ""
			(at 275.59 137.16 0)
			(effects
				(font
					(size 1.27 1.27)
					(thickness 0.15)
				)
				(justify left bottom)
				(hide yes)
			)
		)
		(property "Description" ""
			(at 260.35 127 0)
			(effects
				(font
					(size 1.27 1.27)
				)
				(hide yes)
			)
		)
		(property "Author" "Antmicro"
			(at 275.59 134.62 0)
			(effects
				(font
					(size 1.27 1.27)
					(thickness 0.15)
				)
				(justify left bottom)
				(hide yes)
			)
		)
		(property "License" "Apache-2.0"
			(at 275.59 137.16 0)
			(effects
				(font
					(size 1.27 1.27)
					(thickness 0.15)
				)
				(justify left bottom)
				(hide yes)
			)
		)
		(pin "1"
		)
		(instances
			(project "usb-c-power-adapter"
				(path ""
					(reference "#PWR026")
					(unit 1)
				)
			)
		)
	)
	(symbol
		(lib_id "antmicropower:GND")
		(at 106.68 97.79 0)
		(mirror y)
		(unit 1)
		(exclude_from_sim no)
		(in_bom yes)
		(on_board yes)
		(dnp no)
		(property "Reference" "#PWR073"
			(at 97.79 100.33 0)
			(effects
				(font
					(size 1.27 1.27)
					(thickness 0.15)
				)
				(justify left bottom)
				(hide yes)
			)
		)
		(property "Value" "GND"
			(at 110.49 99.06 0)
			(effects
				(font
					(size 1.27 1.27)
					(thickness 0.15)
				)
			)
		)
		(property "Footprint" ""
			(at 97.79 105.41 0)
			(effects
				(font
					(size 1.27 1.27)
					(thickness 0.15)
				)
				(justify left bottom)
				(hide yes)
			)
		)
		(property "Datasheet" ""
			(at 97.79 110.49 0)
			(effects
				(font
					(size 1.27 1.27)
					(thickness 0.15)
				)
				(justify left bottom)
				(hide yes)
			)
		)
		(property "Description" ""
			(at 106.68 97.79 0)
			(effects
				(font
					(size 1.27 1.27)
				)
				(hide yes)
			)
		)
		(property "Author" "Antmicro"
			(at 97.79 105.41 0)
			(effects
				(font
					(size 1.27 1.27)
					(thickness 0.15)
				)
				(justify left bottom)
				(hide yes)
			)
		)
		(property "License" "Apache-2.0"
			(at 97.79 107.95 0)
			(effects
				(font
					(size 1.27 1.27)
					(thickness 0.15)
				)
				(justify left bottom)
				(hide yes)
			)
		)
		(pin "1"
		)
		(instances
			(project "usb-c-power-adapter"
				(path ""
					(reference "#PWR073")
					(unit 1)
				)
			)
		)
	)
	(symbol
		(lib_id "antmicroTestPoints:TP_0.75mm_SMD")
		(at 195.58 60.96 180)
		(unit 1)
		(exclude_from_sim no)
		(in_bom no)
		(on_board yes)
		(dnp no)
		(property "Reference" "TP8"
			(at 189.23 60.96 0)
			(effects
				(font
					(size 1.27 1.27)
					(thickness 0.15)
				)
			)
		)
		(property "Value" "TP_0.75mm_SMD"
			(at 184.785 57.15 0)
			(effects
				(font
					(size 1.27 1.27)
					(thickness 0.15)
				)
				(justify left bottom)
				(hide yes)
			)
		)
		(property "Footprint" "antmicro-footprints:TP_SMD_0.75mm"
			(at 184.785 54.61 0)
			(effects
				(font
					(size 1.27 1.27)
					(thickness 0.15)
				)
				(justify left bottom)
				(hide yes)
			)
		)
		(property "Datasheet" ""
			(at 177.8 48.26 0)
			(effects
				(font
					(size 1.27 1.27)
					(thickness 0.15)
				)
				(justify left bottom)
				(hide yes)
			)
		)
		(property "Description" "SMT test point"
			(at 195.58 60.96 0)
			(effects
				(font
					(size 1.27 1.27)
				)
				(hide yes)
			)
		)
		(property "MPN" ""
			(at 184.785 49.53 0)
			(effects
				(font
					(size 1.27 1.27)
					(thickness 0.15)
				)
				(justify left bottom)
				(hide yes)
			)
		)
		(property "Manufacturer" ""
			(at 184.785 54.61 0)
			(effects
				(font
					(size 1.27 1.27)
					(thickness 0.15)
				)
				(justify left bottom)
				(hide yes)
			)
		)
		(property "Author" "Antmicro"
			(at 184.785 52.07 0)
			(effects
				(font
					(size 1.27 1.27)
					(thickness 0.15)
				)
				(justify left bottom)
				(hide yes)
			)
		)
		(property "License" "Apache-2.0"
			(at 184.785 49.53 0)
			(effects
				(font
					(size 1.27 1.27)
					(thickness 0.15)
				)
				(justify left bottom)
				(hide yes)
			)
		)
		(pin "1"
		)
		(instances
			(project "usb-c-power-adapter"
				(path ""
					(reference "TP8")
					(unit 1)
				)
			)
		)
	)
	(symbol
		(lib_id "antmicroTestPoints:TP_0.75mm_SMD")
		(at 86.36 52.07 90)
		(unit 1)
		(exclude_from_sim no)
		(in_bom no)
		(on_board yes)
		(dnp no)
		(property "Reference" "TP3"
			(at 85.09 45.72 90)
			(effects
				(font
					(size 1.27 1.27)
					(thickness 0.15)
				)
				(justify right)
			)
		)
		(property "Value" "TP_0.75mm_SMD"
			(at 90.17 41.275 0)
			(effects
				(font
					(size 1.27 1.27)
					(thickness 0.15)
				)
				(justify left bottom)
				(hide yes)
			)
		)
		(property "Footprint" "antmicro-footprints:TP_SMD_0.75mm"
			(at 92.71 41.275 0)
			(effects
				(font
					(size 1.27 1.27)
					(thickness 0.15)
				)
				(justify left bottom)
				(hide yes)
			)
		)
		(property "Datasheet" ""
			(at 99.06 34.29 0)
			(effects
				(font
					(size 1.27 1.27)
					(thickness 0.15)
				)
				(justify left bottom)
				(hide yes)
			)
		)
		(property "Description" "SMT test point"
			(at 86.36 52.07 0)
			(effects
				(font
					(size 1.27 1.27)
				)
				(hide yes)
			)
		)
		(property "MPN" ""
			(at 97.79 41.275 0)
			(effects
				(font
					(size 1.27 1.27)
					(thickness 0.15)
				)
				(justify left bottom)
				(hide yes)
			)
		)
		(property "Manufacturer" ""
			(at 92.71 41.275 0)
			(effects
				(font
					(size 1.27 1.27)
					(thickness 0.15)
				)
				(justify left bottom)
				(hide yes)
			)
		)
		(property "Author" "Antmicro"
			(at 95.25 41.275 0)
			(effects
				(font
					(size 1.27 1.27)
					(thickness 0.15)
				)
				(justify left bottom)
				(hide yes)
			)
		)
		(property "License" "Apache-2.0"
			(at 97.79 41.275 0)
			(effects
				(font
					(size 1.27 1.27)
					(thickness 0.15)
				)
				(justify left bottom)
				(hide yes)
			)
		)
		(pin "1"
		)
		(instances
			(project "usb-c-power-adapter"
				(path ""
					(reference "TP3")
					(unit 1)
				)
			)
		)
	)
	(symbol
		(lib_id "antmicroLEDIndicationDiscrete:LED_G_0603_LG_L29K-G2J1-24-Z")
		(at 260.35 143.51 90)
		(unit 1)
		(exclude_from_sim no)
		(in_bom yes)
		(on_board yes)
		(dnp no)
		(fields_autoplaced yes)
		(property "Reference" "D7"
			(at 262.89 139.7 90)
			(effects
				(font
					(size 1.27 1.27)
					(thickness 0.15)
				)
				(justify right)
			)
		)
		(property "Value" "LED_G_0603_LG_L29K-G2J1-24-Z"
			(at 267.97 123.19 0)
			(effects
				(font
					(size 1.27 1.27)
					(thickness 0.15)
				)
				(justify left bottom)
				(hide yes)
			)
		)
		(property "Footprint" "antmicro-footprints:LED_0603_1608Metric_G"
			(at 270.51 123.19 0)
			(effects
				(font
					(size 1.27 1.27)
					(thickness 0.15)
				)
				(justify left bottom)
				(hide yes)
			)
		)
		(property "Datasheet" "https://look.ams-osram.com/m/19ee86b3ae0ee95b/original/LG-L29K.pdf"
			(at 273.05 123.19 0)
			(effects
				(font
					(size 1.27 1.27)
					(thickness 0.15)
				)
				(justify left bottom)
				(hide yes)
			)
		)
		(property "Description" "LED, Green, SMD, 0603, 20 mA, 1.7 V, 570 nm"
			(at 260.35 143.51 0)
			(effects
				(font
					(size 1.27 1.27)
				)
				(hide yes)
			)
		)
		(property "MPN" "LG L29K-G2J1-24-Z"
			(at 275.59 123.19 0)
			(effects
				(font
					(size 1.27 1.27)
					(thickness 0.15)
				)
				(justify left bottom)
				(hide yes)
			)
		)
		(property "Manufacturer" "OSRAM"
			(at 278.13 123.19 0)
			(effects
				(font
					(size 1.27 1.27)
					(thickness 0.15)
				)
				(justify left bottom)
				(hide yes)
			)
		)
		(property "Color" "Green"
			(at 262.89 142.2399 90)
			(effects
				(font
					(size 1.27 1.27)
				)
				(justify right)
			)
		)
		(property "Author" "Antmicro"
			(at 280.67 123.19 0)
			(effects
				(font
					(size 1.27 1.27)
					(thickness 0.15)
				)
				(justify left bottom)
				(hide yes)
			)
		)
		(property "License" "Apache-2.0"
			(at 283.21 123.19 0)
			(effects
				(font
					(size 1.27 1.27)
					(thickness 0.15)
				)
				(justify left bottom)
				(hide yes)
			)
		)
		(pin "2"
		)
		(pin "1"
		)
		(instances
			(project "usb-c-power-adapter"
				(path ""
					(reference "D7")
					(unit 1)
				)
			)
		)
	)
	(symbol
		(lib_id "antmicroResistors0402:R_100R_0402")
		(at 309.88 73.66 0)
		(unit 1)
		(exclude_from_sim no)
		(in_bom yes)
		(on_board yes)
		(dnp no)
		(fields_autoplaced yes)
		(property "Reference" "R33"
			(at 312.42 67.31 0)
			(effects
				(font
					(size 1.27 1.27)
					(thickness 0.15)
				)
			)
		)
		(property "Value" "R_100R_0402"
			(at 330.2 86.36 0)
			(effects
				(font
					(size 1.27 1.27)
					(thickness 0.15)
				)
				(justify left bottom)
				(hide yes)
			)
		)
		(property "Footprint" "antmicro-footprints:R_0402_1005Metric"
			(at 330.2 88.9 0)
			(effects
				(font
					(size 1.27 1.27)
					(thickness 0.15)
				)
				(justify left bottom)
				(hide yes)
			)
		)
		(property "Datasheet" "https://www.bourns.com/docs/product-datasheets/cr.pdf"
			(at 330.2 91.44 0)
			(effects
				(font
					(size 1.27 1.27)
					(thickness 0.15)
				)
				(justify left bottom)
				(hide yes)
			)
		)
		(property "Description" "SMD Chip Resistor, 100 ohm, ± 1%, 62.5 mW, 0402 [1005 Metric], Thick Film, General Purpose"
			(at 309.88 73.66 0)
			(effects
				(font
					(size 1.27 1.27)
				)
				(hide yes)
			)
		)
		(property "MPN" "CR0402-FX-1000GLF"
			(at 330.2 93.98 0)
			(effects
				(font
					(size 1.27 1.27)
					(thickness 0.15)
				)
				(justify left bottom)
				(hide yes)
			)
		)
		(property "Manufacturer" "Bourns"
			(at 330.2 96.52 0)
			(effects
				(font
					(size 1.27 1.27)
					(thickness 0.15)
				)
				(justify left bottom)
				(hide yes)
			)
		)
		(property "License" "Apache-2.0"
			(at 330.2 99.06 0)
			(effects
				(font
					(size 1.27 1.27)
					(thickness 0.15)
				)
				(justify left bottom)
				(hide yes)
			)
		)
		(property "Author" "Antmicro"
			(at 330.2 101.6 0)
			(effects
				(font
					(size 1.27 1.27)
					(thickness 0.15)
				)
				(justify left bottom)
				(hide yes)
			)
		)
		(property "Val" "100R"
			(at 312.42 69.85 0)
			(effects
				(font
					(size 1.27 1.27)
					(thickness 0.15)
				)
			)
		)
		(property "Tolerance" "1%"
			(at 330.2 83.82 0)
			(effects
				(font
					(size 1.27 1.27)
				)
				(justify left bottom)
				(hide yes)
			)
		)
		(pin "2"
		)
		(pin "1"
		)
		(instances
			(project "usb-c-power-adapter"
				(path ""
					(reference "R33")
					(unit 1)
				)
			)
		)
	)
	(symbol
		(lib_id "antmicroTestPoints:TP_0.75mm_SMD")
		(at 320.04 59.69 90)
		(unit 1)
		(exclude_from_sim no)
		(in_bom no)
		(on_board yes)
		(dnp no)
		(property "Reference" "TP4"
			(at 318.77 53.34 90)
			(effects
				(font
					(size 1.27 1.27)
					(thickness 0.15)
				)
				(justify right)
			)
		)
		(property "Value" "TP_0.75mm_SMD"
			(at 323.85 48.895 0)
			(effects
				(font
					(size 1.27 1.27)
					(thickness 0.15)
				)
				(justify left bottom)
				(hide yes)
			)
		)
		(property "Footprint" "antmicro-footprints:TP_SMD_0.75mm"
			(at 326.39 48.895 0)
			(effects
				(font
					(size 1.27 1.27)
					(thickness 0.15)
				)
				(justify left bottom)
				(hide yes)
			)
		)
		(property "Datasheet" ""
			(at 332.74 41.91 0)
			(effects
				(font
					(size 1.27 1.27)
					(thickness 0.15)
				)
				(justify left bottom)
				(hide yes)
			)
		)
		(property "Description" "SMT test point"
			(at 320.04 59.69 0)
			(effects
				(font
					(size 1.27 1.27)
				)
				(hide yes)
			)
		)
		(property "MPN" ""
			(at 331.47 48.895 0)
			(effects
				(font
					(size 1.27 1.27)
					(thickness 0.15)
				)
				(justify left bottom)
				(hide yes)
			)
		)
		(property "Manufacturer" ""
			(at 326.39 48.895 0)
			(effects
				(font
					(size 1.27 1.27)
					(thickness 0.15)
				)
				(justify left bottom)
				(hide yes)
			)
		)
		(property "Author" "Antmicro"
			(at 328.93 48.895 0)
			(effects
				(font
					(size 1.27 1.27)
					(thickness 0.15)
				)
				(justify left bottom)
				(hide yes)
			)
		)
		(property "License" "Apache-2.0"
			(at 331.47 48.895 0)
			(effects
				(font
					(size 1.27 1.27)
					(thickness 0.15)
				)
				(justify left bottom)
				(hide yes)
			)
		)
		(pin "1"
		)
		(instances
			(project "usb-c-power-adapter"
				(path ""
					(reference "TP4")
					(unit 1)
				)
			)
		)
	)
	(symbol
		(lib_id "antmicropower:GND")
		(at 181.61 64.77 0)
		(unit 1)
		(exclude_from_sim no)
		(in_bom yes)
		(on_board yes)
		(dnp no)
		(property "Reference" "#PWR085"
			(at 190.5 67.31 0)
			(effects
				(font
					(size 1.27 1.27)
					(thickness 0.15)
				)
				(justify left bottom)
				(hide yes)
			)
		)
		(property "Value" "GND"
			(at 181.61 68.58 0)
			(effects
				(font
					(size 1.27 1.27)
					(thickness 0.15)
				)
			)
		)
		(property "Footprint" ""
			(at 190.5 72.39 0)
			(effects
				(font
					(size 1.27 1.27)
					(thickness 0.15)
				)
				(justify left bottom)
				(hide yes)
			)
		)
		(property "Datasheet" ""
			(at 190.5 77.47 0)
			(effects
				(font
					(size 1.27 1.27)
					(thickness 0.15)
				)
				(justify left bottom)
				(hide yes)
			)
		)
		(property "Description" ""
			(at 181.61 64.77 0)
			(effects
				(font
					(size 1.27 1.27)
				)
				(hide yes)
			)
		)
		(property "Author" "Antmicro"
			(at 190.5 72.39 0)
			(effects
				(font
					(size 1.27 1.27)
					(thickness 0.15)
				)
				(justify left bottom)
				(hide yes)
			)
		)
		(property "License" "Apache-2.0"
			(at 190.5 74.93 0)
			(effects
				(font
					(size 1.27 1.27)
					(thickness 0.15)
				)
				(justify left bottom)
				(hide yes)
			)
		)
		(pin "1"
		)
		(instances
			(project "usb-c-power-adapter"
				(path ""
					(reference "#PWR085")
					(unit 1)
				)
			)
		)
	)
	(symbol
		(lib_id "antmicroCapacitors0402:C_100n_50V_X8L_0402")
		(at 163.83 147.32 90)
		(unit 1)
		(exclude_from_sim no)
		(in_bom yes)
		(on_board yes)
		(dnp no)
		(fields_autoplaced yes)
		(property "Reference" "C28"
			(at 166.37 143.5036 90)
			(effects
				(font
					(size 1.27 1.27)
					(thickness 0.15)
				)
				(justify right)
			)
		)
		(property "Value" "C_100n_50V_X8L_0402"
			(at 186.69 132.08 0)
			(effects
				(font
					(size 1.27 1.27)
					(thickness 0.15)
				)
				(justify left bottom)
				(hide yes)
			)
		)
		(property "Footprint" "antmicro-footprints:C_0402_1005Metric"
			(at 189.23 132.08 0)
			(effects
				(font
					(size 1.27 1.27)
					(thickness 0.15)
				)
				(justify left bottom)
				(hide yes)
			)
		)
		(property "Datasheet" "https://www.murata.com/products/productdetail?partno=GCM155L8EH104KE07%23"
			(at 191.77 132.08 0)
			(effects
				(font
					(size 1.27 1.27)
					(thickness 0.15)
				)
				(justify left bottom)
				(hide yes)
			)
		)
		(property "Description" "SMD Multilayer Ceramic Capacitor, 100nF, 50V, 0402, ±10%, X8L"
			(at 163.83 147.32 0)
			(effects
				(font
					(size 1.27 1.27)
				)
				(hide yes)
			)
		)
		(property "MPN" "GCM155L8EH104KE07D"
			(at 194.31 132.08 0)
			(effects
				(font
					(size 1.27 1.27)
					(thickness 0.15)
				)
				(justify left bottom)
				(hide yes)
			)
		)
		(property "Val" "100n"
			(at 166.37 146.0436 90)
			(effects
				(font
					(size 1.27 1.27)
					(thickness 0.15)
				)
				(justify right)
			)
		)
		(property "Voltage" "50V"
			(at 173.99 132.08 0)
			(effects
				(font
					(size 1.27 1.27)
					(thickness 0.15)
				)
				(justify left bottom)
				(hide yes)
			)
		)
		(property "Dielectric" "X8L"
			(at 176.53 132.08 0)
			(effects
				(font
					(size 1.27 1.27)
					(thickness 0.15)
				)
				(justify left bottom)
				(hide yes)
			)
		)
		(property "Manufacturer" "Murata"
			(at 179.07 132.08 0)
			(effects
				(font
					(size 1.27 1.27)
					(thickness 0.15)
				)
				(justify left bottom)
				(hide yes)
			)
		)
		(property "License" "Apache-2.0"
			(at 181.61 132.08 0)
			(effects
				(font
					(size 1.27 1.27)
					(thickness 0.15)
				)
				(justify left bottom)
				(hide yes)
			)
		)
		(property "Author" "Antmicro"
			(at 184.15 132.08 0)
			(effects
				(font
					(size 1.27 1.27)
					(thickness 0.15)
				)
				(justify left bottom)
				(hide yes)
			)
		)
		(pin "1"
		)
		(pin "2"
		)
		(instances
			(project "usb-c-power-adapter"
				(path ""
					(reference "C28")
					(unit 1)
				)
			)
		)
	)
	(symbol
		(lib_id "antmicroDiodesRectifiersSingle:PMEG6002EJ,115")
		(at 146.05 68.58 270)
		(mirror x)
		(unit 1)
		(exclude_from_sim no)
		(in_bom yes)
		(on_board yes)
		(dnp no)
		(property "Reference" "D1"
			(at 148.59 64.77 90)
			(effects
				(font
					(size 1.27 1.27)
					(thickness 0.15)
				)
				(justify left)
			)
		)
		(property "Value" "PMEG6002EJ,115"
			(at 127 67.31 90)
			(effects
				(font
					(size 1.27 1.27)
					(thickness 0.15)
				)
				(justify left)
				(hide yes)
			)
		)
		(property "Footprint" "antmicro-footprints:D_SOD-323F"
			(at 135.89 46.99 0)
			(effects
				(font
					(size 1.27 1.27)
					(thickness 0.15)
				)
				(justify left bottom)
				(hide yes)
			)
		)
		(property "Datasheet" "https://assets.nexperia.com/documents/data-sheet/PMEG6002EJ.pdf"
			(at 133.35 46.99 0)
			(effects
				(font
					(size 1.27 1.27)
					(thickness 0.15)
				)
				(justify left bottom)
				(hide yes)
			)
		)
		(property "Description" "Schottky Rectifier, Low VF, 60 V, 200 mA, Single, SOD-323F, 2 Pins, 600 mV"
			(at 146.05 68.58 0)
			(effects
				(font
					(size 1.27 1.27)
				)
				(hide yes)
			)
		)
		(property "MPN" "PMEG6002EJ,115"
			(at 142.24 74.93 0)
			(effects
				(font
					(size 1.27 1.27)
					(thickness 0.15)
				)
				(justify left bottom)
			)
		)
		(property "Manufacturer" "Nexperia"
			(at 128.27 46.99 0)
			(effects
				(font
					(size 1.27 1.27)
					(thickness 0.15)
				)
				(justify left bottom)
				(hide yes)
			)
		)
		(property "Author" "Antmicro"
			(at 125.73 46.99 0)
			(effects
				(font
					(size 1.27 1.27)
					(thickness 0.15)
				)
				(justify left bottom)
				(hide yes)
			)
		)
		(property "License" "Apache-2.0"
			(at 123.19 46.99 0)
			(effects
				(font
					(size 1.27 1.27)
					(thickness 0.15)
				)
				(justify left bottom)
				(hide yes)
			)
		)
		(pin "2"
		)
		(pin "1"
		)
		(instances
			(project "usb-c-power-adapter"
				(path ""
					(reference "D1")
					(unit 1)
				)
			)
		)
	)
	(symbol
		(lib_id "antmicropower:+3V3")
		(at 179.07 124.46 0)
		(unit 1)
		(exclude_from_sim no)
		(in_bom yes)
		(on_board yes)
		(dnp no)
		(fields_autoplaced yes)
		(property "Reference" "#PWR057"
			(at 194.31 124.46 0)
			(effects
				(font
					(size 1.27 1.27)
					(thickness 0.15)
				)
				(justify left bottom)
				(hide yes)
			)
		)
		(property "Value" "+3V3"
			(at 179.07 119.38 0)
			(effects
				(font
					(size 1.27 1.27)
					(thickness 0.15)
				)
			)
		)
		(property "Footprint" ""
			(at 194.31 132.08 0)
			(effects
				(font
					(size 1.27 1.27)
					(thickness 0.15)
				)
				(justify left bottom)
				(hide yes)
			)
		)
		(property "Datasheet" ""
			(at 194.31 134.62 0)
			(effects
				(font
					(size 1.27 1.27)
					(thickness 0.15)
				)
				(justify left bottom)
				(hide yes)
			)
		)
		(property "Description" ""
			(at 179.07 124.46 0)
			(effects
				(font
					(size 1.27 1.27)
				)
				(hide yes)
			)
		)
		(property "Author" "Antmicro"
			(at 194.31 127 0)
			(effects
				(font
					(size 1.27 1.27)
					(thickness 0.15)
				)
				(justify left bottom)
				(hide yes)
			)
		)
		(property "License" "Apache-2.0"
			(at 194.31 129.54 0)
			(effects
				(font
					(size 1.27 1.27)
					(thickness 0.15)
				)
				(justify left bottom)
				(hide yes)
			)
		)
		(pin "1"
		)
		(instances
			(project "usb-c-power-adapter"
				(path ""
					(reference "#PWR057")
					(unit 1)
				)
			)
		)
	)
	(symbol
		(lib_id "antmicroTestPoints:TP_0.75mm_SMD")
		(at 252.73 63.5 0)
		(unit 1)
		(exclude_from_sim no)
		(in_bom no)
		(on_board yes)
		(dnp no)
		(fields_autoplaced yes)
		(property "Reference" "TP11"
			(at 257.81 63.5 0)
			(effects
				(font
					(size 1.27 1.27)
					(thickness 0.15)
				)
				(justify left)
			)
		)
		(property "Value" "TP_0.75mm_SMD"
			(at 263.525 67.31 0)
			(effects
				(font
					(size 1.27 1.27)
					(thickness 0.15)
				)
				(justify left bottom)
				(hide yes)
			)
		)
		(property "Footprint" "antmicro-footprints:TP_SMD_0.75mm"
			(at 263.525 69.85 0)
			(effects
				(font
					(size 1.27 1.27)
					(thickness 0.15)
				)
				(justify left bottom)
				(hide yes)
			)
		)
		(property "Datasheet" ""
			(at 270.51 76.2 0)
			(effects
				(font
					(size 1.27 1.27)
					(thickness 0.15)
				)
				(justify left bottom)
				(hide yes)
			)
		)
		(property "Description" "SMT test point"
			(at 252.73 63.5 0)
			(effects
				(font
					(size 1.27 1.27)
				)
				(hide yes)
			)
		)
		(property "MPN" ""
			(at 263.525 74.93 0)
			(effects
				(font
					(size 1.27 1.27)
					(thickness 0.15)
				)
				(justify left bottom)
				(hide yes)
			)
		)
		(property "Manufacturer" ""
			(at 263.525 69.85 0)
			(effects
				(font
					(size 1.27 1.27)
					(thickness 0.15)
				)
				(justify left bottom)
				(hide yes)
			)
		)
		(property "Author" "Antmicro"
			(at 263.525 72.39 0)
			(effects
				(font
					(size 1.27 1.27)
					(thickness 0.15)
				)
				(justify left bottom)
				(hide yes)
			)
		)
		(property "License" "Apache-2.0"
			(at 263.525 74.93 0)
			(effects
				(font
					(size 1.27 1.27)
					(thickness 0.15)
				)
				(justify left bottom)
				(hide yes)
			)
		)
		(pin "1"
		)
		(instances
			(project "usb-c-power-adapter"
				(path ""
					(reference "TP11")
					(unit 1)
				)
			)
		)
	)
	(symbol
		(lib_id "antmicropower:PWR_FLAG")
		(at 347.98 86.36 0)
		(unit 1)
		(exclude_from_sim no)
		(in_bom yes)
		(on_board yes)
		(dnp no)
		(property "Reference" "#FLG01"
			(at 347.98 84.455 0)
			(effects
				(font
					(size 1.27 1.27)
				)
				(hide yes)
			)
		)
		(property "Value" "PWR_FLAG"
			(at 347.98 81.28 0)
			(effects
				(font
					(size 1.27 1.27)
				)
			)
		)
		(property "Footprint" ""
			(at 347.98 86.36 0)
			(effects
				(font
					(size 1.27 1.27)
				)
				(hide yes)
			)
		)
		(property "Datasheet" ""
			(at 347.98 86.36 0)
			(effects
				(font
					(size 1.27 1.27)
				)
				(hide yes)
			)
		)
		(property "Description" ""
			(at 347.98 86.36 0)
			(effects
				(font
					(size 1.27 1.27)
				)
				(hide yes)
			)
		)
		(pin "1"
		)
		(instances
			(project "usb-c-power-adapter"
				(path ""
					(reference "#FLG01")
					(unit 1)
				)
			)
		)
	)
	(symbol
		(lib_id "antmicroTVSDiodes:TVS2200DRVR")
		(at 99.06 111.76 0)
		(mirror y)
		(unit 1)
		(exclude_from_sim no)
		(in_bom yes)
		(on_board yes)
		(dnp no)
		(fields_autoplaced yes)
		(property "Reference" "U8"
			(at 93.98 104.14 0)
			(effects
				(font
					(size 1.27 1.27)
				)
			)
		)
		(property "Value" "TVS2200DRVR"
			(at 96.52 107.95 0)
			(effects
				(font
					(size 1.27 1.27)
				)
				(justify left)
				(hide yes)
			)
		)
		(property "Footprint" "antmicro-footprints:WSON-6-1EP_2x2mm_P0.65mm"
			(at 97.79 111.74 0)
			(effects
				(font
					(size 1.27 1.27)
				)
				(justify left bottom)
				(hide yes)
			)
		)
		(property "Datasheet" "https://www.ti.com/lit/ds/symlink/tvs2200.pdf?ts=1712230685180&ref_url=https%253A%252F%252Fwww.ti.com%252Fproduct%252FTVS2200"
			(at 97.79 114.74 0)
			(effects
				(font
					(size 1.27 1.27)
				)
				(justify left bottom)
				(hide yes)
			)
		)
		(property "Description" "ESD Protection Device, 1 kV, WSON-6, 22 V, 105 pF"
			(at 99.06 111.76 0)
			(effects
				(font
					(size 1.27 1.27)
				)
				(hide yes)
			)
		)
		(property "MPN" "TVS2200DRVR"
			(at 93.98 106.68 0)
			(effects
				(font
					(size 1.27 1.27)
				)
			)
		)
		(property "Manufacturer" "Texas Instruments"
			(at 97.79 120.65 0)
			(effects
				(font
					(size 1.27 1.27)
				)
				(justify left bottom)
				(hide yes)
			)
		)
		(property "License" "Apache-2.0"
			(at 97.79 125.73 0)
			(effects
				(font
					(size 1.27 1.27)
				)
				(justify left bottom)
				(hide yes)
			)
		)
		(property "Author" "Antmicro"
			(at 97.79 123.19 0)
			(effects
				(font
					(size 1.27 1.27)
				)
				(justify left bottom)
				(hide yes)
			)
		)
		(pin "2"
		)
		(pin "3"
		)
		(pin "4"
		)
		(pin "6"
		)
		(pin "1"
		)
		(pin "7"
		)
		(pin "5"
		)
		(instances
			(project "usb-c-power-adapter"
				(path ""
					(reference "U8")
					(unit 1)
				)
			)
		)
	)
	(symbol
		(lib_id "antmicroPMICPowerDistributionSwitchesLoadDrivers:STUSB4500_QFN")
		(at 217.17 50.8 0)
		(unit 1)
		(exclude_from_sim no)
		(in_bom yes)
		(on_board yes)
		(dnp no)
		(fields_autoplaced yes)
		(property "Reference" "U1"
			(at 232.41 43.18 0)
			(effects
				(font
					(size 1.27 1.27)
					(thickness 0.15)
				)
			)
		)
		(property "Value" "STUSB4500_QFN"
			(at 262.89 59.69 0)
			(effects
				(font
					(size 1.27 1.27)
					(thickness 0.15)
				)
				(justify left bottom)
				(hide yes)
			)
		)
		(property "Footprint" "antmicro-footprints:QFN-24-1EP_4x4mm_P0.5_EP2.1x2.1mm"
			(at 262.89 62.23 0)
			(effects
				(font
					(size 1.27 1.27)
					(thickness 0.15)
				)
				(justify left bottom)
				(hide yes)
			)
		)
		(property "Datasheet" "https://www.mouser.com/datasheet/2/389/dm00489312-1799262.pdf"
			(at 262.89 64.77 0)
			(effects
				(font
					(size 1.27 1.27)
					(thickness 0.15)
				)
				(justify left bottom)
				(hide yes)
			)
		)
		(property "Description" "USB Controller USB 2.0 I2C Interface 24-QFN (4x4)"
			(at 217.17 50.8 0)
			(effects
				(font
					(size 1.27 1.27)
				)
				(hide yes)
			)
		)
		(property "MPN" "STUSB4500QTR"
			(at 232.41 45.72 0)
			(effects
				(font
					(size 1.27 1.27)
					(thickness 0.15)
				)
			)
		)
		(property "Manufacturer" "STMicroelectronics"
			(at 262.89 67.31 0)
			(effects
				(font
					(size 1.27 1.27)
					(thickness 0.15)
				)
				(justify left bottom)
				(hide yes)
			)
		)
		(property "Author" "Antmicro"
			(at 262.89 69.85 0)
			(effects
				(font
					(size 1.27 1.27)
					(thickness 0.15)
				)
				(justify left bottom)
				(hide yes)
			)
		)
		(property "License" "Apache-2.0"
			(at 262.89 72.39 0)
			(effects
				(font
					(size 1.27 1.27)
					(thickness 0.15)
				)
				(justify left bottom)
				(hide yes)
			)
		)
		(pin "23"
		)
		(pin "6"
		)
		(pin "24"
		)
		(pin "9"
		)
		(pin "19"
		)
		(pin "7"
		)
		(pin "5"
		)
		(pin "18"
		)
		(pin "4"
		)
		(pin "14"
		)
		(pin "1"
		)
		(pin "10"
		)
		(pin "16"
		)
		(pin "13"
		)
		(pin "22"
		)
		(pin "12"
		)
		(pin "11"
		)
		(pin "3"
		)
		(pin "25"
		)
		(pin "2"
		)
		(pin "15"
		)
		(pin "8"
		)
		(pin "17"
		)
		(pin "21"
		)
		(pin "20"
		)
		(instances
			(project "usb-c-power-adapter"
				(path ""
					(reference "U1")
					(unit 1)
				)
			)
		)
	)
	(symbol
		(lib_id "antmicropower:+3V3")
		(at 171.45 124.46 0)
		(unit 1)
		(exclude_from_sim no)
		(in_bom yes)
		(on_board yes)
		(dnp no)
		(fields_autoplaced yes)
		(property "Reference" "#PWR056"
			(at 186.69 124.46 0)
			(effects
				(font
					(size 1.27 1.27)
					(thickness 0.15)
				)
				(justify left bottom)
				(hide yes)
			)
		)
		(property "Value" "+3V3"
			(at 171.45 119.38 0)
			(effects
				(font
					(size 1.27 1.27)
					(thickness 0.15)
				)
			)
		)
		(property "Footprint" ""
			(at 186.69 132.08 0)
			(effects
				(font
					(size 1.27 1.27)
					(thickness 0.15)
				)
				(justify left bottom)
				(hide yes)
			)
		)
		(property "Datasheet" ""
			(at 186.69 134.62 0)
			(effects
				(font
					(size 1.27 1.27)
					(thickness 0.15)
				)
				(justify left bottom)
				(hide yes)
			)
		)
		(property "Description" ""
			(at 171.45 124.46 0)
			(effects
				(font
					(size 1.27 1.27)
				)
				(hide yes)
			)
		)
		(property "Author" "Antmicro"
			(at 186.69 127 0)
			(effects
				(font
					(size 1.27 1.27)
					(thickness 0.15)
				)
				(justify left bottom)
				(hide yes)
			)
		)
		(property "License" "Apache-2.0"
			(at 186.69 129.54 0)
			(effects
				(font
					(size 1.27 1.27)
					(thickness 0.15)
				)
				(justify left bottom)
				(hide yes)
			)
		)
		(pin "1"
		)
		(instances
			(project "usb-c-power-adapter"
				(path ""
					(reference "#PWR056")
					(unit 1)
				)
			)
		)
	)
	(symbol
		(lib_id "antmicropower:GND")
		(at 339.09 88.9 0)
		(mirror y)
		(unit 1)
		(exclude_from_sim no)
		(in_bom yes)
		(on_board yes)
		(dnp no)
		(fields_autoplaced yes)
		(property "Reference" "#PWR04"
			(at 330.2 91.44 0)
			(effects
				(font
					(size 1.27 1.27)
					(thickness 0.15)
				)
				(justify left bottom)
				(hide yes)
			)
		)
		(property "Value" "GND"
			(at 339.09 93.345 0)
			(effects
				(font
					(size 1.27 1.27)
					(thickness 0.15)
				)
			)
		)
		(property "Footprint" ""
			(at 330.2 96.52 0)
			(effects
				(font
					(size 1.27 1.27)
					(thickness 0.15)
				)
				(justify left bottom)
				(hide yes)
			)
		)
		(property "Datasheet" ""
			(at 330.2 101.6 0)
			(effects
				(font
					(size 1.27 1.27)
					(thickness 0.15)
				)
				(justify left bottom)
				(hide yes)
			)
		)
		(property "Description" ""
			(at 339.09 88.9 0)
			(effects
				(font
					(size 1.27 1.27)
				)
				(hide yes)
			)
		)
		(property "Author" "Antmicro"
			(at 330.2 96.52 0)
			(effects
				(font
					(size 1.27 1.27)
					(thickness 0.15)
				)
				(justify left bottom)
				(hide yes)
			)
		)
		(property "License" "Apache-2.0"
			(at 330.2 99.06 0)
			(effects
				(font
					(size 1.27 1.27)
					(thickness 0.15)
				)
				(justify left bottom)
				(hide yes)
			)
		)
		(pin "1"
		)
		(instances
			(project "usb-c-power-adapter"
				(path ""
					(reference "#PWR04")
					(unit 1)
				)
			)
		)
	)
	(symbol
		(lib_id "antmicroCapacitors0402:C_4u7_25V_0402")
		(at 105.41 59.69 90)
		(unit 1)
		(exclude_from_sim no)
		(in_bom yes)
		(on_board yes)
		(dnp no)
		(fields_autoplaced yes)
		(property "Reference" "C27"
			(at 107.95 55.8736 90)
			(effects
				(font
					(size 1.27 1.27)
					(thickness 0.15)
				)
				(justify right)
			)
		)
		(property "Value" "C_4u7_25V_0402"
			(at 115.57 39.37 0)
			(effects
				(font
					(size 1.27 1.27)
					(thickness 0.15)
				)
				(justify left bottom)
				(hide yes)
			)
		)
		(property "Footprint" "antmicro-footprints:C_0402_1005Metric"
			(at 118.11 39.37 0)
			(effects
				(font
					(size 1.27 1.27)
					(thickness 0.15)
				)
				(justify left bottom)
				(hide yes)
			)
		)
		(property "Datasheet" "https://www.murata.com/products/productdetail?partno=GRM155C61E475ME15%23"
			(at 120.65 39.37 0)
			(effects
				(font
					(size 1.27 1.27)
					(thickness 0.15)
				)
				(justify left bottom)
				(hide yes)
			)
		)
		(property "Description" "SMD Multilayer Ceramic Capacitor"
			(at 105.41 59.69 0)
			(effects
				(font
					(size 1.27 1.27)
				)
				(hide yes)
			)
		)
		(property "MPN" "GRM155C61E475ME15J"
			(at 123.19 39.37 0)
			(effects
				(font
					(size 1.27 1.27)
					(thickness 0.15)
				)
				(justify left bottom)
				(hide yes)
			)
		)
		(property "Manufacturer" "Murata"
			(at 125.73 39.37 0)
			(effects
				(font
					(size 1.27 1.27)
					(thickness 0.15)
				)
				(justify left bottom)
				(hide yes)
			)
		)
		(property "License" "Apache-2.0"
			(at 128.27 39.37 0)
			(effects
				(font
					(size 1.27 1.27)
					(thickness 0.15)
				)
				(justify left bottom)
				(hide yes)
			)
		)
		(property "Author" "Antmicro"
			(at 130.81 39.37 0)
			(effects
				(font
					(size 1.27 1.27)
					(thickness 0.15)
				)
				(justify left bottom)
				(hide yes)
			)
		)
		(property "Val" "4u7"
			(at 107.95 58.4136 90)
			(effects
				(font
					(size 1.27 1.27)
					(thickness 0.15)
				)
				(justify right)
			)
		)
		(property "Voltage" "25V"
			(at 133.35 39.37 0)
			(effects
				(font
					(size 1.27 1.27)
				)
				(justify left bottom)
				(hide yes)
			)
		)
		(property "Dielectric" "X5S"
			(at 135.89 39.37 0)
			(effects
				(font
					(size 1.27 1.27)
				)
				(justify left bottom)
				(hide yes)
			)
		)
		(pin "2"
		)
		(pin "1"
		)
		(instances
			(project "usb-c-power-adapter"
				(path ""
					(reference "C27")
					(unit 1)
				)
			)
		)
	)
	(symbol
		(lib_id "antmicroResistors0402:R_1k_0402")
		(at 156.21 80.01 90)
		(unit 1)
		(exclude_from_sim no)
		(in_bom yes)
		(on_board yes)
		(dnp no)
		(fields_autoplaced yes)
		(property "Reference" "R20"
			(at 158.75 76.2 90)
			(effects
				(font
					(size 1.27 1.27)
					(thickness 0.15)
				)
				(justify right)
			)
		)
		(property "Value" "R_1k_0402"
			(at 168.91 59.69 0)
			(effects
				(font
					(size 1.27 1.27)
					(thickness 0.15)
				)
				(justify left bottom)
				(hide yes)
			)
		)
		(property "Footprint" "antmicro-footprints:R_0402_1005Metric"
			(at 171.45 59.69 0)
			(effects
				(font
					(size 1.27 1.27)
					(thickness 0.15)
				)
				(justify left bottom)
				(hide yes)
			)
		)
		(property "Datasheet" "https://www.bourns.com/docs/product-datasheets/cr.pdf"
			(at 173.99 59.69 0)
			(effects
				(font
					(size 1.27 1.27)
					(thickness 0.15)
				)
				(justify left bottom)
				(hide yes)
			)
		)
		(property "Description" "SMD Chip Resistor, 1 kohm, ± 1%, 63 mW, 0402 [1005 Metric], Thick Film, General Purpose"
			(at 156.21 80.01 0)
			(effects
				(font
					(size 1.27 1.27)
				)
				(hide yes)
			)
		)
		(property "MPN" "CR0402-FX-1001GLF"
			(at 176.53 59.69 0)
			(effects
				(font
					(size 1.27 1.27)
					(thickness 0.15)
				)
				(justify left bottom)
				(hide yes)
			)
		)
		(property "Manufacturer" "Bourns"
			(at 179.07 59.69 0)
			(effects
				(font
					(size 1.27 1.27)
					(thickness 0.15)
				)
				(justify left bottom)
				(hide yes)
			)
		)
		(property "License" "Apache-2.0"
			(at 181.61 59.69 0)
			(effects
				(font
					(size 1.27 1.27)
					(thickness 0.15)
				)
				(justify left bottom)
				(hide yes)
			)
		)
		(property "Author" "Antmicro"
			(at 184.15 59.69 0)
			(effects
				(font
					(size 1.27 1.27)
					(thickness 0.15)
				)
				(justify left bottom)
				(hide yes)
			)
		)
		(property "Val" "1k"
			(at 158.75 78.74 90)
			(effects
				(font
					(size 1.27 1.27)
					(thickness 0.15)
				)
				(justify right)
			)
		)
		(property "Tolerance" "1%"
			(at 166.37 59.69 0)
			(effects
				(font
					(size 1.27 1.27)
				)
				(justify left bottom)
				(hide yes)
			)
		)
		(pin "2"
		)
		(pin "1"
		)
		(instances
			(project "usb-c-power-adapter"
				(path ""
					(reference "R20")
					(unit 1)
				)
			)
		)
	)
	(symbol
		(lib_id "antmicropower:GND")
		(at 147.32 148.59 0)
		(unit 1)
		(exclude_from_sim no)
		(in_bom yes)
		(on_board yes)
		(dnp no)
		(property "Reference" "#PWR050"
			(at 156.21 151.13 0)
			(effects
				(font
					(size 1.27 1.27)
					(thickness 0.15)
				)
				(justify left bottom)
				(hide yes)
			)
		)
		(property "Value" "GND"
			(at 147.32 153.035 0)
			(effects
				(font
					(size 1.27 1.27)
					(thickness 0.15)
				)
			)
		)
		(property "Footprint" ""
			(at 156.21 156.21 0)
			(effects
				(font
					(size 1.27 1.27)
					(thickness 0.15)
				)
				(justify left bottom)
				(hide yes)
			)
		)
		(property "Datasheet" ""
			(at 156.21 161.29 0)
			(effects
				(font
					(size 1.27 1.27)
					(thickness 0.15)
				)
				(justify left bottom)
				(hide yes)
			)
		)
		(property "Description" ""
			(at 147.32 148.59 0)
			(effects
				(font
					(size 1.27 1.27)
				)
				(hide yes)
			)
		)
		(property "Author" "Antmicro"
			(at 156.21 156.21 0)
			(effects
				(font
					(size 1.27 1.27)
					(thickness 0.15)
				)
				(justify left bottom)
				(hide yes)
			)
		)
		(property "License" "Apache-2.0"
			(at 156.21 158.75 0)
			(effects
				(font
					(size 1.27 1.27)
					(thickness 0.15)
				)
				(justify left bottom)
				(hide yes)
			)
		)
		(pin "1"
		)
		(instances
			(project "usb-c-power-adapter"
				(path ""
					(reference "#PWR050")
					(unit 1)
				)
			)
		)
	)
	(symbol
		(lib_id "antmicropower:GND")
		(at 67.31 91.44 0)
		(unit 1)
		(exclude_from_sim no)
		(in_bom yes)
		(on_board yes)
		(dnp no)
		(fields_autoplaced yes)
		(property "Reference" "#PWR045"
			(at 76.2 93.98 0)
			(effects
				(font
					(size 1.27 1.27)
					(thickness 0.15)
				)
				(justify left bottom)
				(hide yes)
			)
		)
		(property "Value" "GND"
			(at 67.31 95.885 0)
			(effects
				(font
					(size 1.27 1.27)
					(thickness 0.15)
				)
			)
		)
		(property "Footprint" ""
			(at 76.2 99.06 0)
			(effects
				(font
					(size 1.27 1.27)
					(thickness 0.15)
				)
				(justify left bottom)
				(hide yes)
			)
		)
		(property "Datasheet" ""
			(at 76.2 104.14 0)
			(effects
				(font
					(size 1.27 1.27)
					(thickness 0.15)
				)
				(justify left bottom)
				(hide yes)
			)
		)
		(property "Description" ""
			(at 67.31 91.44 0)
			(effects
				(font
					(size 1.27 1.27)
				)
				(hide yes)
			)
		)
		(property "Author" "Antmicro"
			(at 76.2 99.06 0)
			(effects
				(font
					(size 1.27 1.27)
					(thickness 0.15)
				)
				(justify left bottom)
				(hide yes)
			)
		)
		(property "License" "Apache-2.0"
			(at 76.2 101.6 0)
			(effects
				(font
					(size 1.27 1.27)
					(thickness 0.15)
				)
				(justify left bottom)
				(hide yes)
			)
		)
		(pin "1"
		)
		(instances
			(project "usb-c-power-adapter"
				(path ""
					(reference "#PWR045")
					(unit 1)
				)
			)
		)
	)
	(symbol
		(lib_id "antmicropower:+3V3")
		(at 163.83 124.46 0)
		(unit 1)
		(exclude_from_sim no)
		(in_bom yes)
		(on_board yes)
		(dnp no)
		(property "Reference" "#PWR053"
			(at 179.07 124.46 0)
			(effects
				(font
					(size 1.27 1.27)
					(thickness 0.15)
				)
				(justify left bottom)
				(hide yes)
			)
		)
		(property "Value" "+3V3"
			(at 163.83 119.38 0)
			(effects
				(font
					(size 1.27 1.27)
					(thickness 0.15)
				)
			)
		)
		(property "Footprint" ""
			(at 179.07 132.08 0)
			(effects
				(font
					(size 1.27 1.27)
					(thickness 0.15)
				)
				(justify left bottom)
				(hide yes)
			)
		)
		(property "Datasheet" ""
			(at 179.07 134.62 0)
			(effects
				(font
					(size 1.27 1.27)
					(thickness 0.15)
				)
				(justify left bottom)
				(hide yes)
			)
		)
		(property "Description" ""
			(at 163.83 124.46 0)
			(effects
				(font
					(size 1.27 1.27)
				)
				(hide yes)
			)
		)
		(property "Author" "Antmicro"
			(at 179.07 127 0)
			(effects
				(font
					(size 1.27 1.27)
					(thickness 0.15)
				)
				(justify left bottom)
				(hide yes)
			)
		)
		(property "License" "Apache-2.0"
			(at 179.07 129.54 0)
			(effects
				(font
					(size 1.27 1.27)
					(thickness 0.15)
				)
				(justify left bottom)
				(hide yes)
			)
		)
		(pin "1"
		)
		(instances
			(project "usb-c-power-adapter"
				(path ""
					(reference "#PWR053")
					(unit 1)
				)
			)
		)
	)
	(symbol
		(lib_id "antmicropower:PWR_FLAG")
		(at 194.31 54.61 0)
		(mirror y)
		(unit 1)
		(exclude_from_sim no)
		(in_bom yes)
		(on_board yes)
		(dnp no)
		(property "Reference" "#FLG06"
			(at 194.31 52.705 0)
			(effects
				(font
					(size 1.27 1.27)
				)
				(hide yes)
			)
		)
		(property "Value" "PWR_FLAG"
			(at 194.31 57.15 0)
			(effects
				(font
					(size 1.27 1.27)
				)
			)
		)
		(property "Footprint" ""
			(at 194.31 54.61 0)
			(effects
				(font
					(size 1.27 1.27)
				)
				(hide yes)
			)
		)
		(property "Datasheet" ""
			(at 194.31 54.61 0)
			(effects
				(font
					(size 1.27 1.27)
				)
				(hide yes)
			)
		)
		(property "Description" ""
			(at 194.31 54.61 0)
			(effects
				(font
					(size 1.27 1.27)
				)
				(hide yes)
			)
		)
		(pin "1"
		)
		(instances
			(project "usb-c-power-adapter"
				(path ""
					(reference "#FLG06")
					(unit 1)
				)
			)
		)
	)
	(symbol
		(lib_id "antmicropower:GND")
		(at 222.25 146.05 0)
		(unit 1)
		(exclude_from_sim no)
		(in_bom yes)
		(on_board yes)
		(dnp no)
		(fields_autoplaced yes)
		(property "Reference" "#PWR061"
			(at 231.14 148.59 0)
			(effects
				(font
					(size 1.27 1.27)
					(thickness 0.15)
				)
				(justify left bottom)
				(hide yes)
			)
		)
		(property "Value" "GND"
			(at 222.25 150.495 0)
			(effects
				(font
					(size 1.27 1.27)
					(thickness 0.15)
				)
			)
		)
		(property "Footprint" ""
			(at 231.14 153.67 0)
			(effects
				(font
					(size 1.27 1.27)
					(thickness 0.15)
				)
				(justify left bottom)
				(hide yes)
			)
		)
		(property "Datasheet" ""
			(at 231.14 158.75 0)
			(effects
				(font
					(size 1.27 1.27)
					(thickness 0.15)
				)
				(justify left bottom)
				(hide yes)
			)
		)
		(property "Description" ""
			(at 222.25 146.05 0)
			(effects
				(font
					(size 1.27 1.27)
				)
				(hide yes)
			)
		)
		(property "Author" "Antmicro"
			(at 231.14 153.67 0)
			(effects
				(font
					(size 1.27 1.27)
					(thickness 0.15)
				)
				(justify left bottom)
				(hide yes)
			)
		)
		(property "License" "Apache-2.0"
			(at 231.14 156.21 0)
			(effects
				(font
					(size 1.27 1.27)
					(thickness 0.15)
				)
				(justify left bottom)
				(hide yes)
			)
		)
		(pin "1"
		)
		(instances
			(project "usb-c-power-adapter"
				(path ""
					(reference "#PWR061")
					(unit 1)
				)
			)
		)
	)
	(symbol
		(lib_id "antmicroResistors0402:R_22k_0402")
		(at 292.1 81.28 90)
		(unit 1)
		(exclude_from_sim no)
		(in_bom yes)
		(on_board yes)
		(dnp no)
		(fields_autoplaced yes)
		(property "Reference" "R22"
			(at 294.64 77.47 90)
			(effects
				(font
					(size 1.27 1.27)
					(thickness 0.15)
				)
				(justify right)
			)
		)
		(property "Value" "R_22k_0402"
			(at 304.8 60.96 0)
			(effects
				(font
					(size 1.27 1.27)
					(thickness 0.15)
				)
				(justify left bottom)
				(hide yes)
			)
		)
		(property "Footprint" "antmicro-footprints:R_0402_1005Metric"
			(at 307.34 60.96 0)
			(effects
				(font
					(size 1.27 1.27)
					(thickness 0.15)
				)
				(justify left bottom)
				(hide yes)
			)
		)
		(property "Datasheet" "https://www.bourns.com/docs/product-datasheets/cr.pdf"
			(at 309.88 60.96 0)
			(effects
				(font
					(size 1.27 1.27)
					(thickness 0.15)
				)
				(justify left bottom)
				(hide yes)
			)
		)
		(property "Description" "SMD Chip Resistor, 22 kohm, ± 1%, 62.5 mW, 0402 [1005 Metric], Thick Film, General Purpose"
			(at 292.1 81.28 0)
			(effects
				(font
					(size 1.27 1.27)
				)
				(hide yes)
			)
		)
		(property "MPN" "CR0402-FX-2202GLF"
			(at 312.42 60.96 0)
			(effects
				(font
					(size 1.27 1.27)
					(thickness 0.15)
				)
				(justify left bottom)
				(hide yes)
			)
		)
		(property "Manufacturer" "Bourns"
			(at 314.96 60.96 0)
			(effects
				(font
					(size 1.27 1.27)
					(thickness 0.15)
				)
				(justify left bottom)
				(hide yes)
			)
		)
		(property "License" "Apache-2.0"
			(at 317.5 60.96 0)
			(effects
				(font
					(size 1.27 1.27)
					(thickness 0.15)
				)
				(justify left bottom)
				(hide yes)
			)
		)
		(property "Author" "Antmicro"
			(at 320.04 60.96 0)
			(effects
				(font
					(size 1.27 1.27)
					(thickness 0.15)
				)
				(justify left bottom)
				(hide yes)
			)
		)
		(property "Val" "22k"
			(at 294.64 80.01 90)
			(effects
				(font
					(size 1.27 1.27)
					(thickness 0.15)
				)
				(justify right)
			)
		)
		(property "Tolerance" "1%"
			(at 302.26 60.96 0)
			(effects
				(font
					(size 1.27 1.27)
				)
				(justify left bottom)
				(hide yes)
			)
		)
		(pin "1"
		)
		(pin "2"
		)
		(instances
			(project "usb-c-power-adapter"
				(path ""
					(reference "R22")
					(unit 1)
				)
			)
		)
	)
	(symbol
		(lib_id "antmicropower:VCC")
		(at 326.39 58.42 0)
		(unit 1)
		(exclude_from_sim no)
		(in_bom yes)
		(on_board yes)
		(dnp no)
		(fields_autoplaced yes)
		(property "Reference" "#PWR031"
			(at 326.39 62.23 0)
			(effects
				(font
					(size 1.27 1.27)
				)
				(hide yes)
			)
		)
		(property "Value" "VCC"
			(at 326.39 53.34 0)
			(effects
				(font
					(size 1.27 1.27)
				)
			)
		)
		(property "Footprint" ""
			(at 326.39 58.42 0)
			(effects
				(font
					(size 1.27 1.27)
				)
				(hide yes)
			)
		)
		(property "Datasheet" ""
			(at 326.39 58.42 0)
			(effects
				(font
					(size 1.27 1.27)
				)
				(hide yes)
			)
		)
		(property "Description" ""
			(at 326.39 58.42 0)
			(effects
				(font
					(size 1.27 1.27)
				)
				(hide yes)
			)
		)
		(pin "1"
		)
		(instances
			(project "usb-c-power-adapter"
				(path ""
					(reference "#PWR031")
					(unit 1)
				)
			)
		)
	)
	(symbol
		(lib_id "antmicroTVSDiodes:TPD4E02B04DQA")
		(at 148.59 165.1 0)
		(mirror y)
		(unit 1)
		(exclude_from_sim no)
		(in_bom yes)
		(on_board yes)
		(dnp no)
		(fields_autoplaced yes)
		(property "Reference" "U6"
			(at 142.875 157.48 0)
			(effects
				(font
					(size 1.27 1.27)
					(thickness 0.15)
				)
			)
		)
		(property "Value" "TPD4E02B04DQA"
			(at 138.43 177.8 90)
			(effects
				(font
					(size 1.27 1.27)
					(thickness 0.15)
				)
				(justify left)
				(hide yes)
			)
		)
		(property "Footprint" "antmicro-footprints:USON-10_2.5x1mm_P0.5mm"
			(at 135.89 170.18 0)
			(effects
				(font
					(size 1.27 1.27)
					(thickness 0.15)
				)
				(justify left bottom)
				(hide yes)
			)
		)
		(property "Datasheet" "http://www.ti.com/lit/ds/symlink/tpd4e02b04.pdf"
			(at 135.89 172.72 0)
			(effects
				(font
					(size 1.27 1.27)
					(thickness 0.15)
				)
				(justify left bottom)
				(hide yes)
			)
		)
		(property "Description" "TVS diode array, 12 kV, USON-10, 3.6 V, 0.33 pF"
			(at 148.59 165.1 0)
			(effects
				(font
					(size 1.27 1.27)
				)
				(hide yes)
			)
		)
		(property "MPN" "TPD4E02B04DQAR"
			(at 142.875 160.02 0)
			(effects
				(font
					(size 1.27 1.27)
					(thickness 0.15)
				)
			)
		)
		(property "Manufacturer" "Texas Instruments"
			(at 135.89 177.8 0)
			(effects
				(font
					(size 1.27 1.27)
					(thickness 0.15)
				)
				(justify left bottom)
				(hide yes)
			)
		)
		(property "Author" "Antmicro"
			(at 135.89 180.34 0)
			(effects
				(font
					(size 1.27 1.27)
					(thickness 0.15)
				)
				(justify left bottom)
				(hide yes)
			)
		)
		(property "License" "Apache-2.0"
			(at 135.89 182.88 0)
			(effects
				(font
					(size 1.27 1.27)
					(thickness 0.15)
				)
				(justify left bottom)
				(hide yes)
			)
		)
		(pin "1"
		)
		(pin "9"
		)
		(pin "2"
		)
		(pin "7"
		)
		(pin "5"
		)
		(pin "6"
		)
		(pin "3"
		)
		(pin "8"
		)
		(pin "10"
		)
		(pin "4"
		)
		(instances
			(project "usb-c-power-adapter"
				(path ""
					(reference "U6")
					(unit 1)
				)
			)
		)
	)
	(symbol
		(lib_id "antmicropower:VBUS")
		(at 146.05 57.15 0)
		(unit 1)
		(exclude_from_sim no)
		(in_bom yes)
		(on_board yes)
		(dnp no)
		(fields_autoplaced yes)
		(property "Reference" "#PWR017"
			(at 146.05 60.96 0)
			(effects
				(font
					(size 1.27 1.27)
				)
				(hide yes)
			)
		)
		(property "Value" "VBUS"
			(at 146.05 52.07 0)
			(effects
				(font
					(size 1.27 1.27)
				)
			)
		)
		(property "Footprint" ""
			(at 146.05 57.15 0)
			(effects
				(font
					(size 1.27 1.27)
				)
				(hide yes)
			)
		)
		(property "Datasheet" ""
			(at 146.05 57.15 0)
			(effects
				(font
					(size 1.27 1.27)
				)
				(hide yes)
			)
		)
		(property "Description" ""
			(at 146.05 57.15 0)
			(effects
				(font
					(size 1.27 1.27)
				)
				(hide yes)
			)
		)
		(pin "1"
		)
		(instances
			(project "usb-c-power-adapter"
				(path ""
					(reference "#PWR017")
					(unit 1)
				)
			)
		)
	)
	(symbol
		(lib_id "antmicropower:PWR_FLAG")
		(at 95.25 50.8 0)
		(unit 1)
		(exclude_from_sim no)
		(in_bom yes)
		(on_board yes)
		(dnp no)
		(property "Reference" "#FLG04"
			(at 95.25 48.895 0)
			(effects
				(font
					(size 1.27 1.27)
				)
				(hide yes)
			)
		)
		(property "Value" "PWR_FLAG"
			(at 95.25 45.72 0)
			(effects
				(font
					(size 1.27 1.27)
				)
			)
		)
		(property "Footprint" ""
			(at 95.25 50.8 0)
			(effects
				(font
					(size 1.27 1.27)
				)
				(hide yes)
			)
		)
		(property "Datasheet" ""
			(at 95.25 50.8 0)
			(effects
				(font
					(size 1.27 1.27)
				)
				(hide yes)
			)
		)
		(property "Description" ""
			(at 95.25 50.8 0)
			(effects
				(font
					(size 1.27 1.27)
				)
				(hide yes)
			)
		)
		(pin "1"
		)
		(instances
			(project "usb-c-power-adapter"
				(path ""
					(reference "#FLG04")
					(unit 1)
				)
			)
		)
	)
	(symbol
		(lib_id "antmicroResistors0402:R_0R_0402")
		(at 163.83 132.08 90)
		(unit 1)
		(exclude_from_sim no)
		(in_bom no)
		(on_board yes)
		(dnp yes)
		(fields_autoplaced yes)
		(property "Reference" "R38"
			(at 166.37 128.27 90)
			(effects
				(font
					(size 1.27 1.27)
					(thickness 0.15)
				)
				(justify right)
			)
		)
		(property "Value" "R_0R_0402"
			(at 176.53 111.76 0)
			(effects
				(font
					(size 1.27 1.27)
					(thickness 0.15)
				)
				(justify left bottom)
				(hide yes)
			)
		)
		(property "Footprint" "antmicro-footprints:R_0402_1005Metric"
			(at 179.07 111.76 0)
			(effects
				(font
					(size 1.27 1.27)
					(thickness 0.15)
				)
				(justify left bottom)
				(hide yes)
			)
		)
		(property "Datasheet" "https://industrial.panasonic.com/cdbs/www-data/pdf/RDA0000/AOA0000C301.pdf"
			(at 181.61 111.76 0)
			(effects
				(font
					(size 1.27 1.27)
					(thickness 0.15)
				)
				(justify left bottom)
				(hide yes)
			)
		)
		(property "Description" "SMD Chip Resistor, Jumper, 0 ohm, 100 mW, 0402 [1005 Metric], Thick Film, General Purpose"
			(at 163.83 132.08 0)
			(effects
				(font
					(size 1.27 1.27)
				)
				(hide yes)
			)
		)
		(property "MPN" "ERJ2GE0R00X"
			(at 184.15 111.76 0)
			(effects
				(font
					(size 1.27 1.27)
					(thickness 0.15)
				)
				(justify left bottom)
				(hide yes)
			)
		)
		(property "Manufacturer" "Panasonic"
			(at 186.69 111.76 0)
			(effects
				(font
					(size 1.27 1.27)
					(thickness 0.15)
				)
				(justify left bottom)
				(hide yes)
			)
		)
		(property "License" "Apache-2.0"
			(at 189.23 111.76 0)
			(effects
				(font
					(size 1.27 1.27)
					(thickness 0.15)
				)
				(justify left bottom)
				(hide yes)
			)
		)
		(property "Author" "Antmicro"
			(at 191.77 111.76 0)
			(effects
				(font
					(size 1.27 1.27)
					(thickness 0.15)
				)
				(justify left bottom)
				(hide yes)
			)
		)
		(property "Val" "0R"
			(at 166.37 130.81 90)
			(effects
				(font
					(size 1.27 1.27)
					(thickness 0.15)
				)
				(justify right)
			)
		)
		(property "Tolerance" "~"
			(at 173.99 111.76 0)
			(effects
				(font
					(size 1.27 1.27)
				)
				(justify left bottom)
				(hide yes)
			)
		)
		(property "Current" "1A"
			(at 194.31 111.76 0)
			(effects
				(font
					(size 1.27 1.27)
					(thickness 0.15)
				)
				(justify left bottom)
				(hide yes)
			)
		)
		(pin "1"
		)
		(pin "2"
		)
		(instances
			(project "usb-c-power-adapter"
				(path ""
					(reference "R38")
					(unit 1)
				)
			)
		)
	)
	(symbol
		(lib_id "antmicroResistors0402:R_470R_0402")
		(at 260.35 135.89 90)
		(unit 1)
		(exclude_from_sim no)
		(in_bom yes)
		(on_board yes)
		(dnp no)
		(fields_autoplaced yes)
		(property "Reference" "R26"
			(at 262.89 132.08 90)
			(effects
				(font
					(size 1.27 1.27)
					(thickness 0.15)
				)
				(justify right)
			)
		)
		(property "Value" "R_470_0402"
			(at 273.05 115.57 0)
			(effects
				(font
					(size 1.27 1.27)
					(thickness 0.15)
				)
				(justify left bottom)
				(hide yes)
			)
		)
		(property "Footprint" "antmicro-footprints:R_0402_1005Metric"
			(at 275.59 115.57 0)
			(effects
				(font
					(size 1.27 1.27)
					(thickness 0.15)
				)
				(justify left bottom)
				(hide yes)
			)
		)
		(property "Datasheet" "https://www.bourns.com/docs/product-datasheets/cr.pdf"
			(at 278.13 115.57 0)
			(effects
				(font
					(size 1.27 1.27)
					(thickness 0.15)
				)
				(justify left bottom)
				(hide yes)
			)
		)
		(property "Description" "SMD Chip Resistor, 470 ohm, ± 1%, 62.5 mW, 0402 [1005 Metric], Thick Film, General Purpose"
			(at 260.35 135.89 0)
			(effects
				(font
					(size 1.27 1.27)
				)
				(hide yes)
			)
		)
		(property "MPN" "CR0402-FX-4700GLF"
			(at 280.67 115.57 0)
			(effects
				(font
					(size 1.27 1.27)
					(thickness 0.15)
				)
				(justify left bottom)
				(hide yes)
			)
		)
		(property "Manufacturer" "Bourns"
			(at 283.21 115.57 0)
			(effects
				(font
					(size 1.27 1.27)
					(thickness 0.15)
				)
				(justify left bottom)
				(hide yes)
			)
		)
		(property "License" "Apache-2.0"
			(at 285.75 115.57 0)
			(effects
				(font
					(size 1.27 1.27)
					(thickness 0.15)
				)
				(justify left bottom)
				(hide yes)
			)
		)
		(property "Author" "Antmicro"
			(at 288.29 115.57 0)
			(effects
				(font
					(size 1.27 1.27)
					(thickness 0.15)
				)
				(justify left bottom)
				(hide yes)
			)
		)
		(property "Val" "470R"
			(at 262.89 134.62 90)
			(effects
				(font
					(size 1.27 1.27)
					(thickness 0.15)
				)
				(justify right)
			)
		)
		(property "Tolerance" "1%"
			(at 270.51 115.57 0)
			(effects
				(font
					(size 1.27 1.27)
				)
				(justify left bottom)
				(hide yes)
			)
		)
		(pin "2"
		)
		(pin "1"
		)
		(instances
			(project "usb-c-power-adapter"
				(path ""
					(reference "R26")
					(unit 1)
				)
			)
		)
	)
	(symbol
		(lib_id "antmicroTVSDiodes:TVS2200DRVR")
		(at 99.06 95.25 0)
		(mirror y)
		(unit 1)
		(exclude_from_sim no)
		(in_bom yes)
		(on_board yes)
		(dnp no)
		(fields_autoplaced yes)
		(property "Reference" "U7"
			(at 93.98 87.63 0)
			(effects
				(font
					(size 1.27 1.27)
				)
			)
		)
		(property "Value" "TVS2200DRVR"
			(at 96.52 91.44 0)
			(effects
				(font
					(size 1.27 1.27)
				)
				(justify left)
				(hide yes)
			)
		)
		(property "Footprint" "antmicro-footprints:WSON-6-1EP_2x2mm_P0.65mm"
			(at 97.79 95.23 0)
			(effects
				(font
					(size 1.27 1.27)
				)
				(justify left bottom)
				(hide yes)
			)
		)
		(property "Datasheet" "https://www.ti.com/lit/ds/symlink/tvs2200.pdf?ts=1712230685180&ref_url=https%253A%252F%252Fwww.ti.com%252Fproduct%252FTVS2200"
			(at 97.79 98.23 0)
			(effects
				(font
					(size 1.27 1.27)
				)
				(justify left bottom)
				(hide yes)
			)
		)
		(property "Description" "ESD Protection Device, 1 kV, WSON-6, 22 V, 105 pF"
			(at 99.06 95.25 0)
			(effects
				(font
					(size 1.27 1.27)
				)
				(hide yes)
			)
		)
		(property "MPN" "TVS2200DRVR"
			(at 93.98 90.17 0)
			(effects
				(font
					(size 1.27 1.27)
				)
			)
		)
		(property "Manufacturer" "Texas Instruments"
			(at 97.79 104.14 0)
			(effects
				(font
					(size 1.27 1.27)
				)
				(justify left bottom)
				(hide yes)
			)
		)
		(property "License" "Apache-2.0"
			(at 97.79 109.22 0)
			(effects
				(font
					(size 1.27 1.27)
				)
				(justify left bottom)
				(hide yes)
			)
		)
		(property "Author" "Antmicro"
			(at 97.79 106.68 0)
			(effects
				(font
					(size 1.27 1.27)
				)
				(justify left bottom)
				(hide yes)
			)
		)
		(pin "2"
		)
		(pin "3"
		)
		(pin "4"
		)
		(pin "6"
		)
		(pin "1"
		)
		(pin "7"
		)
		(pin "5"
		)
		(instances
			(project "usb-c-power-adapter"
				(path ""
					(reference "U7")
					(unit 1)
				)
			)
		)
	)
	(symbol
		(lib_id "antmicroCapacitors0402:C_1u_25V_0402")
		(at 260.35 91.44 90)
		(unit 1)
		(exclude_from_sim no)
		(in_bom yes)
		(on_board yes)
		(dnp no)
		(fields_autoplaced yes)
		(property "Reference" "C8"
			(at 262.89 87.6236 90)
			(effects
				(font
					(size 1.27 1.27)
					(thickness 0.15)
				)
				(justify right)
			)
		)
		(property "Value" "C_1u_25V_0402"
			(at 270.51 71.12 0)
			(effects
				(font
					(size 1.27 1.27)
					(thickness 0.15)
				)
				(justify left bottom)
				(hide yes)
			)
		)
		(property "Footprint" "antmicro-footprints:C_0402_1005Metric"
			(at 273.05 71.12 0)
			(effects
				(font
					(size 1.27 1.27)
					(thickness 0.15)
				)
				(justify left bottom)
				(hide yes)
			)
		)
		(property "Datasheet" "https://www.murata.com/products/productdetail?partno=GRM155R61E105KE11%23"
			(at 275.59 71.12 0)
			(effects
				(font
					(size 1.27 1.27)
					(thickness 0.15)
				)
				(justify left bottom)
				(hide yes)
			)
		)
		(property "Description" "SMD Multilayer Ceramic Capacitor, 1 µF, 25 V, 0402 [1005 Metric], ± 10%, X5R, GRM Series"
			(at 260.35 91.44 0)
			(effects
				(font
					(size 1.27 1.27)
				)
				(hide yes)
			)
		)
		(property "MPN" "GRM155R61E105KE11J"
			(at 278.13 71.12 0)
			(effects
				(font
					(size 1.27 1.27)
					(thickness 0.15)
				)
				(justify left bottom)
				(hide yes)
			)
		)
		(property "Manufacturer" "Murata"
			(at 280.67 71.12 0)
			(effects
				(font
					(size 1.27 1.27)
					(thickness 0.15)
				)
				(justify left bottom)
				(hide yes)
			)
		)
		(property "License" "Apache-2.0"
			(at 283.21 71.12 0)
			(effects
				(font
					(size 1.27 1.27)
					(thickness 0.15)
				)
				(justify left bottom)
				(hide yes)
			)
		)
		(property "Author" "Antmicro"
			(at 285.75 71.12 0)
			(effects
				(font
					(size 1.27 1.27)
					(thickness 0.15)
				)
				(justify left bottom)
				(hide yes)
			)
		)
		(property "Val" "1u"
			(at 262.89 90.1636 90)
			(effects
				(font
					(size 1.27 1.27)
					(thickness 0.15)
				)
				(justify right)
			)
		)
		(property "Voltage" "25V"
			(at 288.29 71.12 0)
			(effects
				(font
					(size 1.27 1.27)
				)
				(justify left bottom)
				(hide yes)
			)
		)
		(property "Dielectric" "X5R"
			(at 290.83 71.12 0)
			(effects
				(font
					(size 1.27 1.27)
				)
				(justify left bottom)
				(hide yes)
			)
		)
		(pin "2"
		)
		(pin "1"
		)
		(instances
			(project "usb-c-power-adapter"
				(path ""
					(reference "C8")
					(unit 1)
				)
			)
		)
	)
	(symbol
		(lib_id "antmicropower:VBUS")
		(at 222.25 127 0)
		(unit 1)
		(exclude_from_sim no)
		(in_bom yes)
		(on_board yes)
		(dnp no)
		(property "Reference" "#PWR060"
			(at 222.25 130.81 0)
			(effects
				(font
					(size 1.27 1.27)
				)
				(hide yes)
			)
		)
		(property "Value" "VBUS"
			(at 222.25 121.92 0)
			(effects
				(font
					(size 1.27 1.27)
				)
			)
		)
		(property "Footprint" ""
			(at 222.25 127 0)
			(effects
				(font
					(size 1.27 1.27)
				)
				(hide yes)
			)
		)
		(property "Datasheet" ""
			(at 222.25 127 0)
			(effects
				(font
					(size 1.27 1.27)
				)
				(hide yes)
			)
		)
		(property "Description" ""
			(at 222.25 127 0)
			(effects
				(font
					(size 1.27 1.27)
				)
				(hide yes)
			)
		)
		(pin "1"
		)
		(instances
			(project "usb-c-power-adapter"
				(path ""
					(reference "#PWR060")
					(unit 1)
				)
			)
		)
	)
	(symbol
		(lib_id "antmicropower:VBUS")
		(at 181.61 46.99 0)
		(mirror y)
		(unit 1)
		(exclude_from_sim no)
		(in_bom yes)
		(on_board yes)
		(dnp no)
		(property "Reference" "#PWR084"
			(at 181.61 50.8 0)
			(effects
				(font
					(size 1.27 1.27)
				)
				(hide yes)
			)
		)
		(property "Value" "VBUS"
			(at 181.61 43.18 0)
			(effects
				(font
					(size 1.27 1.27)
				)
			)
		)
		(property "Footprint" ""
			(at 181.61 46.99 0)
			(effects
				(font
					(size 1.27 1.27)
				)
				(hide yes)
			)
		)
		(property "Datasheet" ""
			(at 181.61 46.99 0)
			(effects
				(font
					(size 1.27 1.27)
				)
				(hide yes)
			)
		)
		(property "Description" ""
			(at 181.61 46.99 0)
			(effects
				(font
					(size 1.27 1.27)
				)
				(hide yes)
			)
		)
		(pin "1"
		)
		(instances
			(project "usb-c-power-adapter"
				(path ""
					(reference "#PWR084")
					(unit 1)
				)
			)
		)
	)
	(symbol
		(lib_id "antmicroCapacitors0402:C_1u_25V_0402")
		(at 181.61 59.69 90)
		(unit 1)
		(exclude_from_sim no)
		(in_bom yes)
		(on_board yes)
		(dnp no)
		(property "Reference" "C11"
			(at 179.07 55.8736 90)
			(effects
				(font
					(size 1.27 1.27)
					(thickness 0.15)
				)
				(justify left)
			)
		)
		(property "Value" "C_1u_25V_0402"
			(at 191.77 39.37 0)
			(effects
				(font
					(size 1.27 1.27)
					(thickness 0.15)
				)
				(justify left bottom)
				(hide yes)
			)
		)
		(property "Footprint" "antmicro-footprints:C_0402_1005Metric"
			(at 194.31 39.37 0)
			(effects
				(font
					(size 1.27 1.27)
					(thickness 0.15)
				)
				(justify left bottom)
				(hide yes)
			)
		)
		(property "Datasheet" "https://www.murata.com/products/productdetail?partno=GRM155R61E105KE11%23"
			(at 196.85 39.37 0)
			(effects
				(font
					(size 1.27 1.27)
					(thickness 0.15)
				)
				(justify left bottom)
				(hide yes)
			)
		)
		(property "Description" "SMD Multilayer Ceramic Capacitor, 1 µF, 25 V, 0402 [1005 Metric], ± 10%, X5R, GRM Series"
			(at 181.61 59.69 0)
			(effects
				(font
					(size 1.27 1.27)
				)
				(hide yes)
			)
		)
		(property "MPN" "GRM155R61E105KE11J"
			(at 199.39 39.37 0)
			(effects
				(font
					(size 1.27 1.27)
					(thickness 0.15)
				)
				(justify left bottom)
				(hide yes)
			)
		)
		(property "Manufacturer" "Murata"
			(at 201.93 39.37 0)
			(effects
				(font
					(size 1.27 1.27)
					(thickness 0.15)
				)
				(justify left bottom)
				(hide yes)
			)
		)
		(property "License" "Apache-2.0"
			(at 204.47 39.37 0)
			(effects
				(font
					(size 1.27 1.27)
					(thickness 0.15)
				)
				(justify left bottom)
				(hide yes)
			)
		)
		(property "Author" "Antmicro"
			(at 207.01 39.37 0)
			(effects
				(font
					(size 1.27 1.27)
					(thickness 0.15)
				)
				(justify left bottom)
				(hide yes)
			)
		)
		(property "Val" "1u"
			(at 179.07 58.4136 90)
			(effects
				(font
					(size 1.27 1.27)
					(thickness 0.15)
				)
				(justify left)
			)
		)
		(property "Voltage" "25V"
			(at 209.55 39.37 0)
			(effects
				(font
					(size 1.27 1.27)
				)
				(justify left bottom)
				(hide yes)
			)
		)
		(property "Dielectric" "X5R"
			(at 212.09 39.37 0)
			(effects
				(font
					(size 1.27 1.27)
				)
				(justify left bottom)
				(hide yes)
			)
		)
		(pin "2"
		)
		(pin "1"
		)
		(instances
			(project "usb-c-power-adapter"
				(path ""
					(reference "C11")
					(unit 1)
				)
			)
		)
	)
	(symbol
		(lib_id "antmicroCapacitors0402:C_1u_25V_0402")
		(at 269.24 91.44 90)
		(unit 1)
		(exclude_from_sim no)
		(in_bom yes)
		(on_board yes)
		(dnp no)
		(fields_autoplaced yes)
		(property "Reference" "C9"
			(at 271.78 87.6236 90)
			(effects
				(font
					(size 1.27 1.27)
					(thickness 0.15)
				)
				(justify right)
			)
		)
		(property "Value" "C_1u_25V_0402"
			(at 279.4 71.12 0)
			(effects
				(font
					(size 1.27 1.27)
					(thickness 0.15)
				)
				(justify left bottom)
				(hide yes)
			)
		)
		(property "Footprint" "antmicro-footprints:C_0402_1005Metric"
			(at 281.94 71.12 0)
			(effects
				(font
					(size 1.27 1.27)
					(thickness 0.15)
				)
				(justify left bottom)
				(hide yes)
			)
		)
		(property "Datasheet" "https://www.murata.com/products/productdetail?partno=GRM155R61E105KE11%23"
			(at 284.48 71.12 0)
			(effects
				(font
					(size 1.27 1.27)
					(thickness 0.15)
				)
				(justify left bottom)
				(hide yes)
			)
		)
		(property "Description" "SMD Multilayer Ceramic Capacitor, 1 µF, 25 V, 0402 [1005 Metric], ± 10%, X5R, GRM Series"
			(at 269.24 91.44 0)
			(effects
				(font
					(size 1.27 1.27)
				)
				(hide yes)
			)
		)
		(property "MPN" "GRM155R61E105KE11J"
			(at 287.02 71.12 0)
			(effects
				(font
					(size 1.27 1.27)
					(thickness 0.15)
				)
				(justify left bottom)
				(hide yes)
			)
		)
		(property "Manufacturer" "Murata"
			(at 289.56 71.12 0)
			(effects
				(font
					(size 1.27 1.27)
					(thickness 0.15)
				)
				(justify left bottom)
				(hide yes)
			)
		)
		(property "License" "Apache-2.0"
			(at 292.1 71.12 0)
			(effects
				(font
					(size 1.27 1.27)
					(thickness 0.15)
				)
				(justify left bottom)
				(hide yes)
			)
		)
		(property "Author" "Antmicro"
			(at 294.64 71.12 0)
			(effects
				(font
					(size 1.27 1.27)
					(thickness 0.15)
				)
				(justify left bottom)
				(hide yes)
			)
		)
		(property "Val" "1u"
			(at 271.78 90.1636 90)
			(effects
				(font
					(size 1.27 1.27)
					(thickness 0.15)
				)
				(justify right)
			)
		)
		(property "Voltage" "25V"
			(at 297.18 71.12 0)
			(effects
				(font
					(size 1.27 1.27)
				)
				(justify left bottom)
				(hide yes)
			)
		)
		(property "Dielectric" "X5R"
			(at 299.72 71.12 0)
			(effects
				(font
					(size 1.27 1.27)
				)
				(justify left bottom)
				(hide yes)
			)
		)
		(pin "2"
		)
		(pin "1"
		)
		(instances
			(project "usb-c-power-adapter"
				(path ""
					(reference "C9")
					(unit 1)
				)
			)
		)
	)
	(symbol
		(lib_id "antmicropower:GND")
		(at 163.83 148.59 0)
		(unit 1)
		(exclude_from_sim no)
		(in_bom yes)
		(on_board yes)
		(dnp no)
		(property "Reference" "#PWR054"
			(at 172.72 151.13 0)
			(effects
				(font
					(size 1.27 1.27)
					(thickness 0.15)
				)
				(justify left bottom)
				(hide yes)
			)
		)
		(property "Value" "GND"
			(at 163.83 153.035 0)
			(effects
				(font
					(size 1.27 1.27)
					(thickness 0.15)
				)
			)
		)
		(property "Footprint" ""
			(at 172.72 156.21 0)
			(effects
				(font
					(size 1.27 1.27)
					(thickness 0.15)
				)
				(justify left bottom)
				(hide yes)
			)
		)
		(property "Datasheet" ""
			(at 172.72 161.29 0)
			(effects
				(font
					(size 1.27 1.27)
					(thickness 0.15)
				)
				(justify left bottom)
				(hide yes)
			)
		)
		(property "Description" ""
			(at 163.83 148.59 0)
			(effects
				(font
					(size 1.27 1.27)
				)
				(hide yes)
			)
		)
		(property "Author" "Antmicro"
			(at 172.72 156.21 0)
			(effects
				(font
					(size 1.27 1.27)
					(thickness 0.15)
				)
				(justify left bottom)
				(hide yes)
			)
		)
		(property "License" "Apache-2.0"
			(at 172.72 158.75 0)
			(effects
				(font
					(size 1.27 1.27)
					(thickness 0.15)
				)
				(justify left bottom)
				(hide yes)
			)
		)
		(pin "1"
		)
		(instances
			(project "usb-c-power-adapter"
				(path ""
					(reference "#PWR054")
					(unit 1)
				)
			)
		)
	)
	(symbol
		(lib_id "antmicropower:GND")
		(at 105.41 60.96 0)
		(unit 1)
		(exclude_from_sim no)
		(in_bom yes)
		(on_board yes)
		(dnp no)
		(fields_autoplaced yes)
		(property "Reference" "#PWR049"
			(at 114.3 63.5 0)
			(effects
				(font
					(size 1.27 1.27)
					(thickness 0.15)
				)
				(justify left bottom)
				(hide yes)
			)
		)
		(property "Value" "GND"
			(at 105.41 65.405 0)
			(effects
				(font
					(size 1.27 1.27)
					(thickness 0.15)
				)
			)
		)
		(property "Footprint" ""
			(at 114.3 68.58 0)
			(effects
				(font
					(size 1.27 1.27)
					(thickness 0.15)
				)
				(justify left bottom)
				(hide yes)
			)
		)
		(property "Datasheet" ""
			(at 114.3 73.66 0)
			(effects
				(font
					(size 1.27 1.27)
					(thickness 0.15)
				)
				(justify left bottom)
				(hide yes)
			)
		)
		(property "Description" ""
			(at 105.41 60.96 0)
			(effects
				(font
					(size 1.27 1.27)
				)
				(hide yes)
			)
		)
		(property "Author" "Antmicro"
			(at 114.3 68.58 0)
			(effects
				(font
					(size 1.27 1.27)
					(thickness 0.15)
				)
				(justify left bottom)
				(hide yes)
			)
		)
		(property "License" "Apache-2.0"
			(at 114.3 71.12 0)
			(effects
				(font
					(size 1.27 1.27)
					(thickness 0.15)
				)
				(justify left bottom)
				(hide yes)
			)
		)
		(pin "1"
		)
		(instances
			(project "usb-c-power-adapter"
				(path ""
					(reference "#PWR049")
					(unit 1)
				)
			)
		)
	)
	(symbol
		(lib_id "antmicropower:GND")
		(at 214.63 177.8 0)
		(unit 1)
		(exclude_from_sim no)
		(in_bom yes)
		(on_board yes)
		(dnp no)
		(fields_autoplaced yes)
		(property "Reference" "#PWR03"
			(at 223.52 180.34 0)
			(effects
				(font
					(size 1.27 1.27)
					(thickness 0.15)
				)
				(justify left bottom)
				(hide yes)
			)
		)
		(property "Value" "GND"
			(at 214.63 182.245 0)
			(effects
				(font
					(size 1.27 1.27)
					(thickness 0.15)
				)
			)
		)
		(property "Footprint" ""
			(at 223.52 185.42 0)
			(effects
				(font
					(size 1.27 1.27)
					(thickness 0.15)
				)
				(justify left bottom)
				(hide yes)
			)
		)
		(property "Datasheet" ""
			(at 223.52 190.5 0)
			(effects
				(font
					(size 1.27 1.27)
					(thickness 0.15)
				)
				(justify left bottom)
				(hide yes)
			)
		)
		(property "Description" ""
			(at 214.63 177.8 0)
			(effects
				(font
					(size 1.27 1.27)
				)
				(hide yes)
			)
		)
		(property "Author" "Antmicro"
			(at 223.52 185.42 0)
			(effects
				(font
					(size 1.27 1.27)
					(thickness 0.15)
				)
				(justify left bottom)
				(hide yes)
			)
		)
		(property "License" "Apache-2.0"
			(at 223.52 187.96 0)
			(effects
				(font
					(size 1.27 1.27)
					(thickness 0.15)
				)
				(justify left bottom)
				(hide yes)
			)
		)
		(pin "1"
		)
		(instances
			(project "usb-c-power-adapter"
				(path ""
					(reference "#PWR03")
					(unit 1)
				)
			)
		)
	)
	(symbol
		(lib_id "antmicropower:GND")
		(at 347.98 88.9 0)
		(mirror y)
		(unit 1)
		(exclude_from_sim no)
		(in_bom yes)
		(on_board yes)
		(dnp no)
		(fields_autoplaced yes)
		(property "Reference" "#PWR065"
			(at 339.09 91.44 0)
			(effects
				(font
					(size 1.27 1.27)
					(thickness 0.15)
				)
				(justify left bottom)
				(hide yes)
			)
		)
		(property "Value" "GND"
			(at 347.98 93.345 0)
			(effects
				(font
					(size 1.27 1.27)
					(thickness 0.15)
				)
			)
		)
		(property "Footprint" ""
			(at 339.09 96.52 0)
			(effects
				(font
					(size 1.27 1.27)
					(thickness 0.15)
				)
				(justify left bottom)
				(hide yes)
			)
		)
		(property "Datasheet" ""
			(at 339.09 101.6 0)
			(effects
				(font
					(size 1.27 1.27)
					(thickness 0.15)
				)
				(justify left bottom)
				(hide yes)
			)
		)
		(property "Description" ""
			(at 347.98 88.9 0)
			(effects
				(font
					(size 1.27 1.27)
				)
				(hide yes)
			)
		)
		(property "Author" "Antmicro"
			(at 339.09 96.52 0)
			(effects
				(font
					(size 1.27 1.27)
					(thickness 0.15)
				)
				(justify left bottom)
				(hide yes)
			)
		)
		(property "License" "Apache-2.0"
			(at 339.09 99.06 0)
			(effects
				(font
					(size 1.27 1.27)
					(thickness 0.15)
				)
				(justify left bottom)
				(hide yes)
			)
		)
		(pin "1"
		)
		(instances
			(project "usb-c-power-adapter"
				(path ""
					(reference "#PWR065")
					(unit 1)
				)
			)
		)
	)
	(symbol
		(lib_id "antmicroResistors0402:R_100k_0402")
		(at 292.1 71.12 90)
		(unit 1)
		(exclude_from_sim no)
		(in_bom yes)
		(on_board yes)
		(dnp no)
		(fields_autoplaced yes)
		(property "Reference" "R21"
			(at 294.64 67.31 90)
			(effects
				(font
					(size 1.27 1.27)
					(thickness 0.15)
				)
				(justify right)
			)
		)
		(property "Value" "R_100k_0402"
			(at 304.8 50.8 0)
			(effects
				(font
					(size 1.27 1.27)
					(thickness 0.15)
				)
				(justify left bottom)
				(hide yes)
			)
		)
		(property "Footprint" "antmicro-footprints:R_0402_1005Metric"
			(at 307.34 50.8 0)
			(effects
				(font
					(size 1.27 1.27)
					(thickness 0.15)
				)
				(justify left bottom)
				(hide yes)
			)
		)
		(property "Datasheet" "https://www.bourns.com/docs/product-datasheets/cr.pdf"
			(at 309.88 50.8 0)
			(effects
				(font
					(size 1.27 1.27)
					(thickness 0.15)
				)
				(justify left bottom)
				(hide yes)
			)
		)
		(property "Description" "SMD Chip Resistor, 100 kohm, ± 1%, 62.5 mW, 0402 [1005 Metric], Thick Film, General Purpose"
			(at 292.1 71.12 0)
			(effects
				(font
					(size 1.27 1.27)
				)
				(hide yes)
			)
		)
		(property "MPN" "CR0402-FX-1003GLF"
			(at 312.42 50.8 0)
			(effects
				(font
					(size 1.27 1.27)
					(thickness 0.15)
				)
				(justify left bottom)
				(hide yes)
			)
		)
		(property "Manufacturer" "Bourns"
			(at 314.96 50.8 0)
			(effects
				(font
					(size 1.27 1.27)
					(thickness 0.15)
				)
				(justify left bottom)
				(hide yes)
			)
		)
		(property "License" "Apache-2.0"
			(at 317.5 50.8 0)
			(effects
				(font
					(size 1.27 1.27)
					(thickness 0.15)
				)
				(justify left bottom)
				(hide yes)
			)
		)
		(property "Author" "Antmicro"
			(at 320.04 50.8 0)
			(effects
				(font
					(size 1.27 1.27)
					(thickness 0.15)
				)
				(justify left bottom)
				(hide yes)
			)
		)
		(property "Val" "100k"
			(at 294.64 69.85 90)
			(effects
				(font
					(size 1.27 1.27)
					(thickness 0.15)
				)
				(justify right)
			)
		)
		(property "Tolerance" "1%"
			(at 302.26 50.8 0)
			(effects
				(font
					(size 1.27 1.27)
				)
				(justify left bottom)
				(hide yes)
			)
		)
		(pin "1"
		)
		(pin "2"
		)
		(instances
			(project "usb-c-power-adapter"
				(path ""
					(reference "R21")
					(unit 1)
				)
			)
		)
	)
	(symbol
		(lib_id "antmicropower:GND")
		(at 248.92 92.71 0)
		(mirror y)
		(unit 1)
		(exclude_from_sim no)
		(in_bom yes)
		(on_board yes)
		(dnp no)
		(fields_autoplaced yes)
		(property "Reference" "#PWR052"
			(at 240.03 95.25 0)
			(effects
				(font
					(size 1.27 1.27)
					(thickness 0.15)
				)
				(justify left bottom)
				(hide yes)
			)
		)
		(property "Value" "GND"
			(at 248.92 97.155 0)
			(effects
				(font
					(size 1.27 1.27)
					(thickness 0.15)
				)
			)
		)
		(property "Footprint" ""
			(at 240.03 100.33 0)
			(effects
				(font
					(size 1.27 1.27)
					(thickness 0.15)
				)
				(justify left bottom)
				(hide yes)
			)
		)
		(property "Datasheet" ""
			(at 240.03 105.41 0)
			(effects
				(font
					(size 1.27 1.27)
					(thickness 0.15)
				)
				(justify left bottom)
				(hide yes)
			)
		)
		(property "Description" ""
			(at 248.92 92.71 0)
			(effects
				(font
					(size 1.27 1.27)
				)
				(hide yes)
			)
		)
		(property "Author" "Antmicro"
			(at 240.03 100.33 0)
			(effects
				(font
					(size 1.27 1.27)
					(thickness 0.15)
				)
				(justify left bottom)
				(hide yes)
			)
		)
		(property "License" "Apache-2.0"
			(at 240.03 102.87 0)
			(effects
				(font
					(size 1.27 1.27)
					(thickness 0.15)
				)
				(justify left bottom)
				(hide yes)
			)
		)
		(pin "1"
		)
		(instances
			(project "usb-c-power-adapter"
				(path ""
					(reference "#PWR052")
					(unit 1)
				)
			)
		)
	)
	(symbol
		(lib_id "antmicropower:VBUS")
		(at 105.41 50.8 0)
		(unit 1)
		(exclude_from_sim no)
		(in_bom yes)
		(on_board yes)
		(dnp no)
		(property "Reference" "#PWR048"
			(at 105.41 54.61 0)
			(effects
				(font
					(size 1.27 1.27)
				)
				(hide yes)
			)
		)
		(property "Value" "VBUS"
			(at 105.41 45.72 0)
			(effects
				(font
					(size 1.27 1.27)
				)
			)
		)
		(property "Footprint" ""
			(at 105.41 50.8 0)
			(effects
				(font
					(size 1.27 1.27)
				)
				(hide yes)
			)
		)
		(property "Datasheet" ""
			(at 105.41 50.8 0)
			(effects
				(font
					(size 1.27 1.27)
				)
				(hide yes)
			)
		)
		(property "Description" ""
			(at 105.41 50.8 0)
			(effects
				(font
					(size 1.27 1.27)
				)
				(hide yes)
			)
		)
		(pin "1"
		)
		(instances
			(project "usb-c-power-adapter"
				(path ""
					(reference "#PWR048")
					(unit 1)
				)
			)
		)
	)
	(symbol
		(lib_id "antmicroLEDIndicationDiscrete:LED_G_0603_LG_L29K-G2J1-24-Z")
		(at 222.25 143.51 90)
		(unit 1)
		(exclude_from_sim no)
		(in_bom yes)
		(on_board yes)
		(dnp no)
		(fields_autoplaced yes)
		(property "Reference" "D3"
			(at 224.79 139.7 90)
			(effects
				(font
					(size 1.27 1.27)
					(thickness 0.15)
				)
				(justify right)
			)
		)
		(property "Value" "LED_G_0603_LG_L29K-G2J1-24-Z"
			(at 229.87 123.19 0)
			(effects
				(font
					(size 1.27 1.27)
					(thickness 0.15)
				)
				(justify left bottom)
				(hide yes)
			)
		)
		(property "Footprint" "antmicro-footprints:LED_0603_1608Metric_G"
			(at 232.41 123.19 0)
			(effects
				(font
					(size 1.27 1.27)
					(thickness 0.15)
				)
				(justify left bottom)
				(hide yes)
			)
		)
		(property "Datasheet" "https://look.ams-osram.com/m/19ee86b3ae0ee95b/original/LG-L29K.pdf"
			(at 234.95 123.19 0)
			(effects
				(font
					(size 1.27 1.27)
					(thickness 0.15)
				)
				(justify left bottom)
				(hide yes)
			)
		)
		(property "Description" "LED, Green, SMD, 0603, 20 mA, 1.7 V, 570 nm"
			(at 222.25 143.51 0)
			(effects
				(font
					(size 1.27 1.27)
				)
				(hide yes)
			)
		)
		(property "MPN" "LG L29K-G2J1-24-Z"
			(at 237.49 123.19 0)
			(effects
				(font
					(size 1.27 1.27)
					(thickness 0.15)
				)
				(justify left bottom)
				(hide yes)
			)
		)
		(property "Manufacturer" "OSRAM"
			(at 240.03 123.19 0)
			(effects
				(font
					(size 1.27 1.27)
					(thickness 0.15)
				)
				(justify left bottom)
				(hide yes)
			)
		)
		(property "Color" "Green"
			(at 224.79 142.2399 90)
			(effects
				(font
					(size 1.27 1.27)
				)
				(justify right)
			)
		)
		(property "Author" "Antmicro"
			(at 242.57 123.19 0)
			(effects
				(font
					(size 1.27 1.27)
					(thickness 0.15)
				)
				(justify left bottom)
				(hide yes)
			)
		)
		(property "License" "Apache-2.0"
			(at 245.11 123.19 0)
			(effects
				(font
					(size 1.27 1.27)
					(thickness 0.15)
				)
				(justify left bottom)
				(hide yes)
			)
		)
		(pin "2"
		)
		(pin "1"
		)
		(instances
			(project "usb-c-power-adapter"
				(path ""
					(reference "D3")
					(unit 1)
				)
			)
		)
	)
	(symbol
		(lib_id "antmicroLEDIndicationDiscrete:LED_G_0603_LG_L29K-G2J1-24-Z")
		(at 241.3 143.51 90)
		(unit 1)
		(exclude_from_sim no)
		(in_bom yes)
		(on_board yes)
		(dnp no)
		(fields_autoplaced yes)
		(property "Reference" "D6"
			(at 243.84 139.7 90)
			(effects
				(font
					(size 1.27 1.27)
					(thickness 0.15)
				)
				(justify right)
			)
		)
		(property "Value" "LED_G_0603_LG_L29K-G2J1-24-Z"
			(at 248.92 123.19 0)
			(effects
				(font
					(size 1.27 1.27)
					(thickness 0.15)
				)
				(justify left bottom)
				(hide yes)
			)
		)
		(property "Footprint" "antmicro-footprints:LED_0603_1608Metric_G"
			(at 251.46 123.19 0)
			(effects
				(font
					(size 1.27 1.27)
					(thickness 0.15)
				)
				(justify left bottom)
				(hide yes)
			)
		)
		(property "Datasheet" "https://look.ams-osram.com/m/19ee86b3ae0ee95b/original/LG-L29K.pdf"
			(at 254 123.19 0)
			(effects
				(font
					(size 1.27 1.27)
					(thickness 0.15)
				)
				(justify left bottom)
				(hide yes)
			)
		)
		(property "Description" "LED, Green, SMD, 0603, 20 mA, 1.7 V, 570 nm"
			(at 241.3 143.51 0)
			(effects
				(font
					(size 1.27 1.27)
				)
				(hide yes)
			)
		)
		(property "MPN" "LG L29K-G2J1-24-Z"
			(at 256.54 123.19 0)
			(effects
				(font
					(size 1.27 1.27)
					(thickness 0.15)
				)
				(justify left bottom)
				(hide yes)
			)
		)
		(property "Manufacturer" "OSRAM"
			(at 259.08 123.19 0)
			(effects
				(font
					(size 1.27 1.27)
					(thickness 0.15)
				)
				(justify left bottom)
				(hide yes)
			)
		)
		(property "Color" "Green"
			(at 243.84 142.2399 90)
			(effects
				(font
					(size 1.27 1.27)
				)
				(justify right)
			)
		)
		(property "Author" "Antmicro"
			(at 261.62 123.19 0)
			(effects
				(font
					(size 1.27 1.27)
					(thickness 0.15)
				)
				(justify left bottom)
				(hide yes)
			)
		)
		(property "License" "Apache-2.0"
			(at 264.16 123.19 0)
			(effects
				(font
					(size 1.27 1.27)
					(thickness 0.15)
				)
				(justify left bottom)
				(hide yes)
			)
		)
		(pin "2"
		)
		(pin "1"
		)
		(instances
			(project "usb-c-power-adapter"
				(path ""
					(reference "D6")
					(unit 1)
				)
			)
		)
	)
	(symbol
		(lib_id "antmicroTestPoints:TP_0.75mm_SMD")
		(at 252.73 60.96 0)
		(unit 1)
		(exclude_from_sim no)
		(in_bom no)
		(on_board yes)
		(dnp no)
		(fields_autoplaced yes)
		(property "Reference" "TP10"
			(at 257.81 60.96 0)
			(effects
				(font
					(size 1.27 1.27)
					(thickness 0.15)
				)
				(justify left)
			)
		)
		(property "Value" "TP_0.75mm_SMD"
			(at 263.525 64.77 0)
			(effects
				(font
					(size 1.27 1.27)
					(thickness 0.15)
				)
				(justify left bottom)
				(hide yes)
			)
		)
		(property "Footprint" "antmicro-footprints:TP_SMD_0.75mm"
			(at 263.525 67.31 0)
			(effects
				(font
					(size 1.27 1.27)
					(thickness 0.15)
				)
				(justify left bottom)
				(hide yes)
			)
		)
		(property "Datasheet" ""
			(at 270.51 73.66 0)
			(effects
				(font
					(size 1.27 1.27)
					(thickness 0.15)
				)
				(justify left bottom)
				(hide yes)
			)
		)
		(property "Description" "SMT test point"
			(at 252.73 60.96 0)
			(effects
				(font
					(size 1.27 1.27)
				)
				(hide yes)
			)
		)
		(property "MPN" ""
			(at 263.525 72.39 0)
			(effects
				(font
					(size 1.27 1.27)
					(thickness 0.15)
				)
				(justify left bottom)
				(hide yes)
			)
		)
		(property "Manufacturer" ""
			(at 263.525 67.31 0)
			(effects
				(font
					(size 1.27 1.27)
					(thickness 0.15)
				)
				(justify left bottom)
				(hide yes)
			)
		)
		(property "Author" "Antmicro"
			(at 263.525 69.85 0)
			(effects
				(font
					(size 1.27 1.27)
					(thickness 0.15)
				)
				(justify left bottom)
				(hide yes)
			)
		)
		(property "License" "Apache-2.0"
			(at 263.525 72.39 0)
			(effects
				(font
					(size 1.27 1.27)
					(thickness 0.15)
				)
				(justify left bottom)
				(hide yes)
			)
		)
		(pin "1"
		)
		(instances
			(project "usb-c-power-adapter"
				(path ""
					(reference "TP10")
					(unit 1)
				)
			)
		)
	)
)
